FILE_TYPE = MACRO_DRAWING;
SET COLOR_WIRE YELLOW;
SET COLOR_PROP ORANGE;
SET COLOR_DOT WHITE;
SET COLOR_ARC YELLOW;
SET COLOR_BODY GREEN;
SET COLOR_NOTE PURPLE;
SET PROP_DISPLAY VALUE;
SET PAGE_NUMBER P41;
FORCEADD GENOA_SP5..5
(-4700 3600);
FORCEPROP 1 LAST LOCATION U26
J 0
(-5345 6431);
DISPLAY 0.489362 (-5345 6431);
PAINT SKYBLUE (-5345 6431);
FORCEPROP 0 LAST $SEC 5
J 0
(-5325 6475);
DISPLAY 0.680851 (-5325 6475);
PAINT MONO (-5325 6475);
DISPLAY INVISIBLE (-5325 6475);
FORCEPROP 0 LAST CDS_SEC 5
J 0
(-5350 6425);
DISPLAY 1.021277 (-5350 6425);
DISPLAY INVISIBLE (-5350 6425);
FORCEPROP 0 LASTPIN (-5500 2975) $PN BC71
J 2
(-5510 2985);
DISPLAY 0.489362 (-5510 2985);
PAINT MONO (-5510 2985);
FORCEPROP 0 LASTPIN (-5500 2925) $PN BD70
J 2
(-5510 2935);
DISPLAY 0.489362 (-5510 2935);
PAINT MONO (-5510 2935);
FORCEPROP 0 LASTPIN (-5500 1825) $PN BF70
J 2
(-5510 1835);
DISPLAY 0.489362 (-5510 1835);
PAINT MONO (-5510 1835);
FORCEPROP 0 LASTPIN (-5500 1775) $PN BG71
J 2
(-5510 1785);
DISPLAY 0.489362 (-5510 1785);
PAINT MONO (-5510 1785);
FORCEPROP 0 LASTPIN (-5500 2125) $PN AT69
J 2
(-5510 2135);
DISPLAY 0.489362 (-5510 2135);
PAINT MONO (-5510 2135);
FORCEPROP 0 LASTPIN (-5500 2025) $PN AU69
J 2
(-5510 2035);
DISPLAY 0.489362 (-5510 2035);
PAINT MONO (-5510 2035);
FORCEPROP 0 LASTPIN (-5500 2825) $PN AV70
J 2
(-5510 2835);
DISPLAY 0.489362 (-5510 2835);
PAINT MONO (-5510 2835);
FORCEPROP 0 LASTPIN (-5500 2775) $PN AW69
J 2
(-5510 2785);
DISPLAY 0.489362 (-5510 2785);
PAINT MONO (-5510 2785);
FORCEPROP 0 LASTPIN (-5500 2675) $PN BN69
J 2
(-5510 2685);
DISPLAY 0.489362 (-5510 2685);
PAINT MONO (-5510 2685);
FORCEPROP 0 LASTPIN (-5500 1675) $PN AU71
J 2
(-5510 1685);
DISPLAY 0.489362 (-5510 1685);
PAINT MONO (-5510 1685);
FORCEPROP 0 LASTPIN (-5500 1625) $PN AV69
J 2
(-5510 1635);
DISPLAY 0.489362 (-5510 1635);
PAINT MONO (-5510 1635);
FORCEPROP 0 LASTPIN (-5500 1525) $PN BP69
J 2
(-5510 1535);
DISPLAY 0.489362 (-5510 1535);
PAINT MONO (-5510 1535);
FORCEPROP 0 LASTPIN (-5500 3825) $PN AW71
J 2
(-5510 3835);
DISPLAY 0.489362 (-5510 3835);
PAINT MONO (-5510 3835);
FORCEPROP 0 LASTPIN (-5500 3775) $PN AY70
J 2
(-5510 3785);
DISPLAY 0.489362 (-5510 3785);
PAINT MONO (-5510 3785);
FORCEPROP 0 LASTPIN (-5500 3725) $PN AY69
J 2
(-5510 3735);
DISPLAY 0.489362 (-5510 3735);
PAINT MONO (-5510 3735);
FORCEPROP 0 LASTPIN (-5500 3675) $PN BA69
J 2
(-5510 3685);
DISPLAY 0.489362 (-5510 3685);
PAINT MONO (-5510 3685);
FORCEPROP 0 LASTPIN (-5500 3625) $PN BA71
J 2
(-5510 3635);
DISPLAY 0.489362 (-5510 3635);
PAINT MONO (-5510 3635);
FORCEPROP 0 LASTPIN (-5500 3575) $PN BB70
J 2
(-5510 3585);
DISPLAY 0.489362 (-5510 3585);
PAINT MONO (-5510 3585);
FORCEPROP 0 LASTPIN (-5500 3525) $PN BB69
J 2
(-5510 3535);
DISPLAY 0.489362 (-5510 3535);
PAINT MONO (-5510 3535);
FORCEPROP 0 LASTPIN (-3900 2375) $PN AJ71
J 0
(-3890 2385);
DISPLAY 0.489362 (-3890 2385);
PAINT MONO (-3890 2385);
FORCEPROP 0 LASTPIN (-3900 2325) $PN AK69
J 0
(-3890 2335);
DISPLAY 0.489362 (-3890 2335);
PAINT MONO (-3890 2335);
FORCEPROP 0 LASTPIN (-3900 2275) $PN AK70
J 0
(-3890 2285);
DISPLAY 0.489362 (-3890 2285);
PAINT MONO (-3890 2285);
FORCEPROP 0 LASTPIN (-3900 2225) $PN AL69
J 0
(-3890 2235);
DISPLAY 0.489362 (-3890 2235);
PAINT MONO (-3890 2235);
FORCEPROP 0 LASTPIN (-3900 2175) $PN AN71
J 0
(-3890 2185);
DISPLAY 0.489362 (-3890 2185);
PAINT MONO (-3890 2185);
FORCEPROP 0 LASTPIN (-3900 2125) $PN AP69
J 0
(-3890 2135);
DISPLAY 0.489362 (-3890 2135);
PAINT MONO (-3890 2135);
FORCEPROP 0 LASTPIN (-3900 2075) $PN AP70
J 0
(-3890 2085);
DISPLAY 0.489362 (-3890 2085);
PAINT MONO (-3890 2085);
FORCEPROP 0 LASTPIN (-3900 2025) $PN AR69
J 0
(-3890 2035);
DISPLAY 0.489362 (-3890 2035);
PAINT MONO (-3890 2035);
FORCEPROP 0 LASTPIN (-3900 5975) $PN E71
J 0
(-3890 5985);
DISPLAY 0.489362 (-3890 5985);
PAINT MONO (-3890 5985);
FORCEPROP 0 LASTPIN (-3900 5925) $PN F69
J 0
(-3890 5935);
DISPLAY 0.489362 (-3890 5935);
PAINT MONO (-3890 5935);
FORCEPROP 0 LASTPIN (-3900 5875) $PN F70
J 0
(-3890 5885);
DISPLAY 0.489362 (-3890 5885);
PAINT MONO (-3890 5885);
FORCEPROP 0 LASTPIN (-3900 5825) $PN G69
J 0
(-3890 5835);
DISPLAY 0.489362 (-3890 5835);
PAINT MONO (-3890 5835);
FORCEPROP 0 LASTPIN (-3900 5775) $PN J71
J 0
(-3890 5785);
DISPLAY 0.489362 (-3890 5785);
PAINT MONO (-3890 5785);
FORCEPROP 0 LASTPIN (-3900 5725) $PN K69
J 0
(-3890 5735);
DISPLAY 0.489362 (-3890 5735);
PAINT MONO (-3890 5735);
FORCEPROP 0 LASTPIN (-3900 5675) $PN K70
J 0
(-3890 5685);
DISPLAY 0.489362 (-3890 5685);
PAINT MONO (-3890 5685);
FORCEPROP 0 LASTPIN (-3900 5625) $PN L69
J 0
(-3890 5635);
DISPLAY 0.489362 (-3890 5635);
PAINT MONO (-3890 5635);
FORCEPROP 0 LASTPIN (-3900 5525) $PN L71
J 0
(-3890 5535);
DISPLAY 0.489362 (-3890 5535);
PAINT MONO (-3890 5535);
FORCEPROP 0 LASTPIN (-3900 5475) $PN M69
J 0
(-3890 5485);
DISPLAY 0.489362 (-3890 5485);
PAINT MONO (-3890 5485);
FORCEPROP 0 LASTPIN (-3900 5425) $PN M70
J 0
(-3890 5435);
DISPLAY 0.489362 (-3890 5435);
PAINT MONO (-3890 5435);
FORCEPROP 0 LASTPIN (-3900 5375) $PN N69
J 0
(-3890 5385);
DISPLAY 0.489362 (-3890 5385);
PAINT MONO (-3890 5385);
FORCEPROP 0 LASTPIN (-3900 5325) $PN R71
J 0
(-3890 5335);
DISPLAY 0.489362 (-3890 5335);
PAINT MONO (-3890 5335);
FORCEPROP 0 LASTPIN (-3900 5275) $PN T69
J 0
(-3890 5285);
DISPLAY 0.489362 (-3890 5285);
PAINT MONO (-3890 5285);
FORCEPROP 0 LASTPIN (-3900 5225) $PN T70
J 0
(-3890 5235);
DISPLAY 0.489362 (-3890 5235);
PAINT MONO (-3890 5235);
FORCEPROP 0 LASTPIN (-3900 5175) $PN U69
J 0
(-3890 5185);
DISPLAY 0.489362 (-3890 5185);
PAINT MONO (-3890 5185);
FORCEPROP 0 LASTPIN (-3900 5075) $PN U71
J 0
(-3890 5085);
DISPLAY 0.489362 (-3890 5085);
PAINT MONO (-3890 5085);
FORCEPROP 0 LASTPIN (-3900 5025) $PN V69
J 0
(-3890 5035);
DISPLAY 0.489362 (-3890 5035);
PAINT MONO (-3890 5035);
FORCEPROP 0 LASTPIN (-3900 4975) $PN V70
J 0
(-3890 4985);
DISPLAY 0.489362 (-3890 4985);
PAINT MONO (-3890 4985);
FORCEPROP 0 LASTPIN (-3900 4925) $PN W69
J 0
(-3890 4935);
DISPLAY 0.489362 (-3890 4935);
PAINT MONO (-3890 4935);
FORCEPROP 0 LASTPIN (-3900 4875) $PN AA71
J 0
(-3890 4885);
DISPLAY 0.489362 (-3890 4885);
PAINT MONO (-3890 4885);
FORCEPROP 0 LASTPIN (-3900 4825) $PN AB69
J 0
(-3890 4835);
DISPLAY 0.489362 (-3890 4835);
PAINT MONO (-3890 4835);
FORCEPROP 0 LASTPIN (-3900 4775) $PN AB70
J 0
(-3890 4785);
DISPLAY 0.489362 (-3890 4785);
PAINT MONO (-3890 4785);
FORCEPROP 0 LASTPIN (-3900 4725) $PN AC69
J 0
(-3890 4735);
DISPLAY 0.489362 (-3890 4735);
PAINT MONO (-3890 4735);
FORCEPROP 0 LASTPIN (-3900 4625) $PN AC71
J 0
(-3890 4635);
DISPLAY 0.489362 (-3890 4635);
PAINT MONO (-3890 4635);
FORCEPROP 0 LASTPIN (-3900 4575) $PN AD69
J 0
(-3890 4585);
DISPLAY 0.489362 (-3890 4585);
PAINT MONO (-3890 4585);
FORCEPROP 0 LASTPIN (-3900 4525) $PN AD70
J 0
(-3890 4535);
DISPLAY 0.489362 (-3890 4535);
PAINT MONO (-3890 4535);
FORCEPROP 0 LASTPIN (-3900 4475) $PN AE69
J 0
(-3890 4485);
DISPLAY 0.489362 (-3890 4485);
PAINT MONO (-3890 4485);
FORCEPROP 0 LASTPIN (-3900 4425) $PN AG71
J 0
(-3890 4435);
DISPLAY 0.489362 (-3890 4435);
PAINT MONO (-3890 4435);
FORCEPROP 0 LASTPIN (-3900 4375) $PN AH69
J 0
(-3890 4385);
DISPLAY 0.489362 (-3890 4385);
PAINT MONO (-3890 4385);
FORCEPROP 0 LASTPIN (-3900 4325) $PN AH70
J 0
(-3890 4335);
DISPLAY 0.489362 (-3890 4335);
PAINT MONO (-3890 4335);
FORCEPROP 0 LASTPIN (-3900 4275) $PN AJ69
J 0
(-3890 4285);
DISPLAY 0.489362 (-3890 4285);
PAINT MONO (-3890 4285);
FORCEPROP 0 LASTPIN (-5500 5975) $PN G71
J 2
(-5510 5985);
DISPLAY 0.489362 (-5510 5985);
PAINT MONO (-5510 5985);
FORCEPROP 0 LASTPIN (-5500 5875) $PN N71
J 2
(-5510 5885);
DISPLAY 0.489362 (-5510 5885);
PAINT MONO (-5510 5885);
FORCEPROP 0 LASTPIN (-5500 5775) $PN W71
J 2
(-5510 5785);
DISPLAY 0.489362 (-5510 5785);
PAINT MONO (-5510 5785);
FORCEPROP 0 LASTPIN (-5500 5675) $PN AE71
J 2
(-5510 5685);
DISPLAY 0.489362 (-5510 5685);
PAINT MONO (-5510 5685);
FORCEPROP 0 LASTPIN (-5500 5575) $PN AL71
J 2
(-5510 5585);
DISPLAY 0.489362 (-5510 5585);
PAINT MONO (-5510 5585);
FORCEPROP 0 LASTPIN (-5500 5475) $PN J69
J 2
(-5510 5485);
DISPLAY 0.489362 (-5510 5485);
PAINT MONO (-5510 5485);
FORCEPROP 0 LASTPIN (-5500 5375) $PN R69
J 2
(-5510 5385);
DISPLAY 0.489362 (-5510 5385);
PAINT MONO (-5510 5385);
FORCEPROP 0 LASTPIN (-5500 5275) $PN AA69
J 2
(-5510 5285);
DISPLAY 0.489362 (-5510 5285);
PAINT MONO (-5510 5285);
FORCEPROP 0 LASTPIN (-5500 5175) $PN AG69
J 2
(-5510 5185);
DISPLAY 0.489362 (-5510 5185);
PAINT MONO (-5510 5185);
FORCEPROP 0 LASTPIN (-5500 5075) $PN AN69
J 2
(-5510 5085);
DISPLAY 0.489362 (-5510 5085);
PAINT MONO (-5510 5085);
FORCEPROP 0 LASTPIN (-5500 5925) $PN H70
J 2
(-5510 5935);
DISPLAY 0.489362 (-5510 5935);
PAINT MONO (-5510 5935);
FORCEPROP 0 LASTPIN (-5500 5825) $PN P70
J 2
(-5510 5835);
DISPLAY 0.489362 (-5510 5835);
PAINT MONO (-5510 5835);
FORCEPROP 0 LASTPIN (-5500 5725) $PN Y70
J 2
(-5510 5735);
DISPLAY 0.489362 (-5510 5735);
PAINT MONO (-5510 5735);
FORCEPROP 0 LASTPIN (-5500 5625) $PN AF70
J 2
(-5510 5635);
DISPLAY 0.489362 (-5510 5635);
PAINT MONO (-5510 5635);
FORCEPROP 0 LASTPIN (-5500 5525) $PN AM70
J 2
(-5510 5535);
DISPLAY 0.489362 (-5510 5535);
PAINT MONO (-5510 5535);
FORCEPROP 0 LASTPIN (-5500 5425) $PN H69
J 2
(-5510 5435);
DISPLAY 0.489362 (-5510 5435);
PAINT MONO (-5510 5435);
FORCEPROP 0 LASTPIN (-5500 5325) $PN P69
J 2
(-5510 5335);
DISPLAY 0.489362 (-5510 5335);
PAINT MONO (-5510 5335);
FORCEPROP 0 LASTPIN (-5500 5225) $PN Y69
J 2
(-5510 5235);
DISPLAY 0.489362 (-5510 5235);
PAINT MONO (-5510 5235);
FORCEPROP 0 LASTPIN (-5500 5125) $PN AF69
J 2
(-5510 5135);
DISPLAY 0.489362 (-5510 5135);
PAINT MONO (-5510 5135);
FORCEPROP 0 LASTPIN (-5500 5025) $PN AM69
J 2
(-5510 5035);
DISPLAY 0.489362 (-5510 5035);
PAINT MONO (-5510 5035);
FORCEPROP 0 LASTPIN (-5500 2575) $PN BC69
J 2
(-5510 2585);
DISPLAY 0.489362 (-5510 2585);
PAINT MONO (-5510 2585);
FORCEPROP 0 LASTPIN (-5500 2475) $PN BM69
J 2
(-5510 2485);
DISPLAY 0.489362 (-5510 2485);
PAINT MONO (-5510 2485);
FORCEPROP 0 LASTPIN (-5500 2425) $PN BN71
J 2
(-5510 2435);
DISPLAY 0.489362 (-5510 2435);
PAINT MONO (-5510 2435);
FORCEPROP 0 LASTPIN (-5500 2325) $PN BP70
J 2
(-5510 2335);
DISPLAY 0.489362 (-5510 2335);
PAINT MONO (-5510 2335);
FORCEPROP 0 LASTPIN (-5500 1425) $PN BL69
J 2
(-5510 1435);
DISPLAY 0.489362 (-5510 1435);
PAINT MONO (-5510 1435);
FORCEPROP 0 LASTPIN (-5500 1375) $PN BM70
J 2
(-5510 1385);
DISPLAY 0.489362 (-5510 1385);
PAINT MONO (-5510 1385);
FORCEPROP 0 LASTPIN (-5500 1275) $PN BR71
J 2
(-5510 1285);
DISPLAY 0.489362 (-5510 1285);
PAINT MONO (-5510 1285);
FORCEPROP 0 LASTPIN (-5500 3425) $PN BG69
J 2
(-5510 3435);
DISPLAY 0.489362 (-5510 3435);
PAINT MONO (-5510 3435);
FORCEPROP 0 LASTPIN (-5500 3375) $PN BH69
J 2
(-5510 3385);
DISPLAY 0.489362 (-5510 3385);
PAINT MONO (-5510 3385);
FORCEPROP 0 LASTPIN (-5500 3325) $PN BH70
J 2
(-5510 3335);
DISPLAY 0.489362 (-5510 3335);
PAINT MONO (-5510 3335);
FORCEPROP 0 LASTPIN (-5500 3275) $PN BJ71
J 2
(-5510 3285);
DISPLAY 0.489362 (-5510 3285);
PAINT MONO (-5510 3285);
FORCEPROP 0 LASTPIN (-5500 3225) $PN BJ69
J 2
(-5510 3235);
DISPLAY 0.489362 (-5510 3235);
PAINT MONO (-5510 3235);
FORCEPROP 0 LASTPIN (-5500 3175) $PN BK69
J 2
(-5510 3185);
DISPLAY 0.489362 (-5510 3185);
PAINT MONO (-5510 3185);
FORCEPROP 0 LASTPIN (-5500 3125) $PN BK70
J 2
(-5510 3135);
DISPLAY 0.489362 (-5510 3135);
PAINT MONO (-5510 3135);
FORCEPROP 0 LASTPIN (-3900 1925) $PN BY70
J 0
(-3890 1935);
DISPLAY 0.489362 (-3890 1935);
PAINT MONO (-3890 1935);
FORCEPROP 0 LASTPIN (-3900 1875) $PN CA69
J 0
(-3890 1885);
DISPLAY 0.489362 (-3890 1885);
PAINT MONO (-3890 1885);
FORCEPROP 0 LASTPIN (-3900 1825) $PN CA71
J 0
(-3890 1835);
DISPLAY 0.489362 (-3890 1835);
PAINT MONO (-3890 1835);
FORCEPROP 0 LASTPIN (-3900 1775) $PN CB69
J 0
(-3890 1785);
DISPLAY 0.489362 (-3890 1785);
PAINT MONO (-3890 1785);
FORCEPROP 0 LASTPIN (-3900 1725) $PN BT70
J 0
(-3890 1735);
DISPLAY 0.489362 (-3890 1735);
PAINT MONO (-3890 1735);
FORCEPROP 0 LASTPIN (-3900 1675) $PN BU69
J 0
(-3890 1685);
DISPLAY 0.489362 (-3890 1685);
PAINT MONO (-3890 1685);
FORCEPROP 0 LASTPIN (-3900 1625) $PN BU71
J 0
(-3890 1635);
DISPLAY 0.489362 (-3890 1635);
PAINT MONO (-3890 1635);
FORCEPROP 0 LASTPIN (-3900 1575) $PN BV69
J 0
(-3890 1585);
DISPLAY 0.489362 (-3890 1585);
PAINT MONO (-3890 1585);
FORCEPROP 0 LASTPIN (-3900 4175) $PN CB70
J 0
(-3890 4185);
DISPLAY 0.489362 (-3890 4185);
PAINT MONO (-3890 4185);
FORCEPROP 0 LASTPIN (-3900 4125) $PN CC69
J 0
(-3890 4135);
DISPLAY 0.489362 (-3890 4135);
PAINT MONO (-3890 4135);
FORCEPROP 0 LASTPIN (-3900 4075) $PN CC71
J 0
(-3890 4085);
DISPLAY 0.489362 (-3890 4085);
PAINT MONO (-3890 4085);
FORCEPROP 0 LASTPIN (-3900 4025) $PN CD69
J 0
(-3890 4035);
DISPLAY 0.489362 (-3890 4035);
PAINT MONO (-3890 4035);
FORCEPROP 0 LASTPIN (-3900 3975) $PN CF70
J 0
(-3890 3985);
DISPLAY 0.489362 (-3890 3985);
PAINT MONO (-3890 3985);
FORCEPROP 0 LASTPIN (-3900 3925) $PN CG69
J 0
(-3890 3935);
DISPLAY 0.489362 (-3890 3935);
PAINT MONO (-3890 3935);
FORCEPROP 0 LASTPIN (-3900 3875) $PN CG71
J 0
(-3890 3885);
DISPLAY 0.489362 (-3890 3885);
PAINT MONO (-3890 3885);
FORCEPROP 0 LASTPIN (-3900 3825) $PN CH69
J 0
(-3890 3835);
DISPLAY 0.489362 (-3890 3835);
PAINT MONO (-3890 3835);
FORCEPROP 0 LASTPIN (-3900 3725) $PN CH70
J 0
(-3890 3735);
DISPLAY 0.489362 (-3890 3735);
PAINT MONO (-3890 3735);
FORCEPROP 0 LASTPIN (-3900 3675) $PN CJ69
J 0
(-3890 3685);
DISPLAY 0.489362 (-3890 3685);
PAINT MONO (-3890 3685);
FORCEPROP 0 LASTPIN (-3900 3625) $PN CJ71
J 0
(-3890 3635);
DISPLAY 0.489362 (-3890 3635);
PAINT MONO (-3890 3635);
FORCEPROP 0 LASTPIN (-3900 3575) $PN CK69
J 0
(-3890 3585);
DISPLAY 0.489362 (-3890 3585);
PAINT MONO (-3890 3585);
FORCEPROP 0 LASTPIN (-3900 3525) $PN CM70
J 0
(-3890 3535);
DISPLAY 0.489362 (-3890 3535);
PAINT MONO (-3890 3535);
FORCEPROP 0 LASTPIN (-3900 3475) $PN CN69
J 0
(-3890 3485);
DISPLAY 0.489362 (-3890 3485);
PAINT MONO (-3890 3485);
FORCEPROP 0 LASTPIN (-3900 3425) $PN CN71
J 0
(-3890 3435);
DISPLAY 0.489362 (-3890 3435);
PAINT MONO (-3890 3435);
FORCEPROP 0 LASTPIN (-3900 3375) $PN CP69
J 0
(-3890 3385);
DISPLAY 0.489362 (-3890 3385);
PAINT MONO (-3890 3385);
FORCEPROP 0 LASTPIN (-3900 3275) $PN CP70
J 0
(-3890 3285);
DISPLAY 0.489362 (-3890 3285);
PAINT MONO (-3890 3285);
FORCEPROP 0 LASTPIN (-3900 3225) $PN CR69
J 0
(-3890 3235);
DISPLAY 0.489362 (-3890 3235);
PAINT MONO (-3890 3235);
FORCEPROP 0 LASTPIN (-3900 3175) $PN CR71
J 0
(-3890 3185);
DISPLAY 0.489362 (-3890 3185);
PAINT MONO (-3890 3185);
FORCEPROP 0 LASTPIN (-3900 3125) $PN CT69
J 0
(-3890 3135);
DISPLAY 0.489362 (-3890 3135);
PAINT MONO (-3890 3135);
FORCEPROP 0 LASTPIN (-3900 3075) $PN CV70
J 0
(-3890 3085);
DISPLAY 0.489362 (-3890 3085);
PAINT MONO (-3890 3085);
FORCEPROP 0 LASTPIN (-3900 3025) $PN CW69
J 0
(-3890 3035);
DISPLAY 0.489362 (-3890 3035);
PAINT MONO (-3890 3035);
FORCEPROP 0 LASTPIN (-3900 2975) $PN CW71
J 0
(-3890 2985);
DISPLAY 0.489362 (-3890 2985);
PAINT MONO (-3890 2985);
FORCEPROP 0 LASTPIN (-3900 2925) $PN CY69
J 0
(-3890 2935);
DISPLAY 0.489362 (-3890 2935);
PAINT MONO (-3890 2935);
FORCEPROP 0 LASTPIN (-3900 2825) $PN CY70
J 0
(-3890 2835);
DISPLAY 0.489362 (-3890 2835);
PAINT MONO (-3890 2835);
FORCEPROP 0 LASTPIN (-3900 2775) $PN DA69
J 0
(-3890 2785);
DISPLAY 0.489362 (-3890 2785);
PAINT MONO (-3890 2785);
FORCEPROP 0 LASTPIN (-3900 2725) $PN DA71
J 0
(-3890 2735);
DISPLAY 0.489362 (-3890 2735);
PAINT MONO (-3890 2735);
FORCEPROP 0 LASTPIN (-3900 2675) $PN DB69
J 0
(-3890 2685);
DISPLAY 0.489362 (-3890 2685);
PAINT MONO (-3890 2685);
FORCEPROP 0 LASTPIN (-3900 2625) $PN DD70
J 0
(-3890 2635);
DISPLAY 0.489362 (-3890 2635);
PAINT MONO (-3890 2635);
FORCEPROP 0 LASTPIN (-3900 2575) $PN DE69
J 0
(-3890 2585);
DISPLAY 0.489362 (-3890 2585);
PAINT MONO (-3890 2585);
FORCEPROP 0 LASTPIN (-3900 2525) $PN DE71
J 0
(-3890 2535);
DISPLAY 0.489362 (-3890 2535);
PAINT MONO (-3890 2535);
FORCEPROP 0 LASTPIN (-3900 2475) $PN DF69
J 0
(-3890 2485);
DISPLAY 0.489362 (-3890 2485);
PAINT MONO (-3890 2485);
FORCEPROP 0 LASTPIN (-5500 4925) $PN CD70
J 2
(-5510 4935);
DISPLAY 0.489362 (-5510 4935);
PAINT MONO (-5510 4935);
FORCEPROP 0 LASTPIN (-5500 4825) $PN CK70
J 2
(-5510 4835);
DISPLAY 0.489362 (-5510 4835);
PAINT MONO (-5510 4835);
FORCEPROP 0 LASTPIN (-5500 4725) $PN CT70
J 2
(-5510 4735);
DISPLAY 0.489362 (-5510 4735);
PAINT MONO (-5510 4735);
FORCEPROP 0 LASTPIN (-5500 4625) $PN DB70
J 2
(-5510 4635);
DISPLAY 0.489362 (-5510 4635);
PAINT MONO (-5510 4635);
FORCEPROP 0 LASTPIN (-5500 4525) $PN BY69
J 2
(-5510 4535);
DISPLAY 0.489362 (-5510 4535);
PAINT MONO (-5510 4535);
FORCEPROP 0 LASTPIN (-5500 4425) $PN CF69
J 2
(-5510 4435);
DISPLAY 0.489362 (-5510 4435);
PAINT MONO (-5510 4435);
FORCEPROP 0 LASTPIN (-5500 4325) $PN CM69
J 2
(-5510 4335);
DISPLAY 0.489362 (-5510 4335);
PAINT MONO (-5510 4335);
FORCEPROP 0 LASTPIN (-5500 4225) $PN CV69
J 2
(-5510 4235);
DISPLAY 0.489362 (-5510 4235);
PAINT MONO (-5510 4235);
FORCEPROP 0 LASTPIN (-5500 4125) $PN DD69
J 2
(-5510 4135);
DISPLAY 0.489362 (-5510 4135);
PAINT MONO (-5510 4135);
FORCEPROP 0 LASTPIN (-5500 4025) $PN BV70
J 2
(-5510 4035);
DISPLAY 0.489362 (-5510 4035);
PAINT MONO (-5510 4035);
FORCEPROP 0 LASTPIN (-5500 4875) $PN CE71
J 2
(-5510 4885);
DISPLAY 0.489362 (-5510 4885);
PAINT MONO (-5510 4885);
FORCEPROP 0 LASTPIN (-5500 4775) $PN CL71
J 2
(-5510 4785);
DISPLAY 0.489362 (-5510 4785);
PAINT MONO (-5510 4785);
FORCEPROP 0 LASTPIN (-5500 4675) $PN CU71
J 2
(-5510 4685);
DISPLAY 0.489362 (-5510 4685);
PAINT MONO (-5510 4685);
FORCEPROP 0 LASTPIN (-5500 4575) $PN DC71
J 2
(-5510 4585);
DISPLAY 0.489362 (-5510 4585);
PAINT MONO (-5510 4585);
FORCEPROP 0 LASTPIN (-5500 4475) $PN BW69
J 2
(-5510 4485);
DISPLAY 0.489362 (-5510 4485);
PAINT MONO (-5510 4485);
FORCEPROP 0 LASTPIN (-5500 4375) $PN CE69
J 2
(-5510 4385);
DISPLAY 0.489362 (-5510 4385);
PAINT MONO (-5510 4385);
FORCEPROP 0 LASTPIN (-5500 4275) $PN CL69
J 2
(-5510 4285);
DISPLAY 0.489362 (-5510 4285);
PAINT MONO (-5510 4285);
FORCEPROP 0 LASTPIN (-5500 4175) $PN CU69
J 2
(-5510 4185);
DISPLAY 0.489362 (-5510 4185);
PAINT MONO (-5510 4185);
FORCEPROP 0 LASTPIN (-5500 4075) $PN DC69
J 2
(-5510 4085);
DISPLAY 0.489362 (-5510 4085);
PAINT MONO (-5510 4085);
FORCEPROP 0 LASTPIN (-5500 3975) $PN BW71
J 2
(-5510 3985);
DISPLAY 0.489362 (-5510 3985);
PAINT MONO (-5510 3985);
FORCEPROP 0 LASTPIN (-5500 2225) $PN BL71
J 2
(-5510 2235);
DISPLAY 0.489362 (-5510 2235);
PAINT MONO (-5510 2235);
FORCEPROP 0 LASTPIN (-5500 1175) $PN BF69
J 2
(-5510 1185);
DISPLAY 0.489362 (-5510 1185);
PAINT MONO (-5510 1185);
FORCEPROP 2 LAST PART_TYPE SMLF
J 0
(-5350 6375);
DISPLAY 1.021277 (-5350 6375);
FORCEPROP 1 LAST MATERIAL IO
J 0
(-5345 6157);
DISPLAY 0.489362 (-5345 6157);
PAINT SKYBLUE (-5345 6157);
FORCEPROP 2 LAST VALUE SOCKET6096_13568-001
J 0
(-5350 6275);
DISPLAY 0.489362 (-5350 6275);
PAINT SKYBLUE (-5350 6275);
FORCEPROP 1 LAST PART_NUMBER DGA^6000030
J 0
(-5345 6284);
DISPLAY 0.489362 (-5345 6284);
PAINT SKYBLUE (-5345 6284);
FORCEPROP 2 LAST CDS_LIB pure_quanta
J 0
(-4700 3600);
DISPLAY INVISIBLE (-4700 3600);
FORCEPROP 1 LAST CDS_LMAN_SYM_OUTLINE -650,2525,650,-2525
J 0
(-4700 3600);
DISPLAY 0.468085 (-4700 3600);
PAINT GREEN (-4700 3600);
DISPLAY INVISIBLE (-4700 3600);
FORCEPROP 1 LAST NEEDS_NO_SIZE TRUE
J 0
(-4700 3600);
DISPLAY 0.723404 (-4700 3600);
PAINT GREEN (-4700 3600);
DISPLAY INVISIBLE (-4700 3600);
FORCEPROP 1 LAST PATH I159
J 0
(-4700 3600);
DISPLAY 0.723404 (-4700 3600);
PAINT GREEN (-4700 3600);
DISPLAY INVISIBLE (-4700 3600);
FORCEADD OFFPAGE..3
(-2700 6000);
FORCEPROP 2 LAST $XR0 101 
J 0
(-2486 6000);
DISPLAY 0.638298 (-2486 6000);
PAINT MONO (-2486 6000);
FORCEPROP 2 LAST PATH I160
J 0
(-2475 6050);
DISPLAY 1.021277 (-2475 6050);
DISPLAY INVISIBLE (-2475 6050);
FORCEPROP 1 LAST COMMENT_BODY TRUE
J 0
(-2750 5900);
DISPLAY 0.872340 (-2750 5900);
PAINT GREEN (-2750 5900);
DISPLAY INVISIBLE (-2750 5900);
FORCEPROP 1 LAST OFFPAGE TRUE
J 0
(-2375 5875);
DISPLAY 0.872340 (-2375 5875);
PAINT GREEN (-2375 5875);
DISPLAY INVISIBLE (-2375 5875);
FORCEPROP 2 LAST CDS_LIB mstr_standard
J 0
(-2700 6000);
DISPLAY 0.723404 (-2700 6000);
PAINT MONO (-2700 6000);
DISPLAY INVISIBLE (-2700 6000);
FORCEADD OFFPAGE..3
(-2700 4200);
FORCEPROP 2 LAST $XR0 101 
J 0
(-2486 4200);
DISPLAY 0.638298 (-2486 4200);
PAINT MONO (-2486 4200);
FORCEPROP 2 LAST PATH I161
J 0
(-2475 4250);
DISPLAY 1.021277 (-2475 4250);
DISPLAY INVISIBLE (-2475 4250);
FORCEPROP 1 LAST COMMENT_BODY TRUE
J 0
(-2750 4100);
DISPLAY 0.872340 (-2750 4100);
PAINT GREEN (-2750 4100);
DISPLAY INVISIBLE (-2750 4100);
FORCEPROP 1 LAST OFFPAGE TRUE
J 0
(-2375 4075);
DISPLAY 0.872340 (-2375 4075);
PAINT GREEN (-2375 4075);
DISPLAY INVISIBLE (-2375 4075);
FORCEPROP 2 LAST CDS_LIB mstr_standard
J 0
(-2700 4200);
DISPLAY 0.723404 (-2700 4200);
PAINT MONO (-2700 4200);
DISPLAY INVISIBLE (-2700 4200);
FORCEADD TAP..1
(-3425 5975);
FORCEPROP 3 LASTPIN (-3475 5975) SIG_NAME M_E_CPU1_SA_DQ<0>
J 0
(-3465 5985);
DISPLAY 0.659574 (-3465 5985);
PAINT MONO (-3465 5985);
DISPLAY INVISIBLE (-3465 5985);
FORCEPROP 1 LASTPIN (-3475 5975) BN 0
J 0
(-3487 5983);
DISPLAY 0.489362 (-3487 5983);
PAINT GREEN (-3487 5983);
FORCEPROP 2 LAST CDS_LIB mstr_standard
J 0
(-3425 5975);
DISPLAY 0.723404 (-3425 5975);
PAINT MONO (-3425 5975);
DISPLAY INVISIBLE (-3425 5975);
FORCEPROP 1 LAST BODY_TYPE PLUMBING
J 0
(-3425 6025);
DISPLAY 0.872340 (-3425 6025);
PAINT GREEN (-3425 6025);
DISPLAY INVISIBLE (-3425 6025);
FORCEPROP 1 LAST HDL_TAP TRUE
J 0
(-3100 5850);
DISPLAY 0.872340 (-3100 5850);
DISPLAY INVISIBLE (-3100 5850);
FORCEPROP 1 LAST PATH I162
J 0
(-3427 5975);
DISPLAY 0.872340 (-3427 5975);
PAINT GREEN (-3427 5975);
DISPLAY INVISIBLE (-3427 5975);
FORCEADD TAP..1
(-3425 5925);
FORCEPROP 3 LASTPIN (-3475 5925) SIG_NAME M_E_CPU1_SA_DQ<1>
J 0
(-3465 5935);
DISPLAY 0.659574 (-3465 5935);
PAINT MONO (-3465 5935);
DISPLAY INVISIBLE (-3465 5935);
FORCEPROP 1 LASTPIN (-3475 5925) BN 1
J 0
(-3487 5933);
DISPLAY 0.489362 (-3487 5933);
PAINT GREEN (-3487 5933);
FORCEPROP 2 LAST CDS_LIB mstr_standard
J 0
(-3425 5925);
DISPLAY 0.723404 (-3425 5925);
PAINT MONO (-3425 5925);
DISPLAY INVISIBLE (-3425 5925);
FORCEPROP 1 LAST BODY_TYPE PLUMBING
J 0
(-3425 5975);
DISPLAY 0.872340 (-3425 5975);
PAINT GREEN (-3425 5975);
DISPLAY INVISIBLE (-3425 5975);
FORCEPROP 1 LAST HDL_TAP TRUE
J 0
(-3100 5800);
DISPLAY 0.872340 (-3100 5800);
DISPLAY INVISIBLE (-3100 5800);
FORCEPROP 1 LAST PATH I163
J 0
(-3427 5925);
DISPLAY 0.872340 (-3427 5925);
PAINT GREEN (-3427 5925);
DISPLAY INVISIBLE (-3427 5925);
FORCEADD TAP..1
(-3425 5875);
FORCEPROP 3 LASTPIN (-3475 5875) SIG_NAME M_E_CPU1_SA_DQ<2>
J 0
(-3465 5885);
DISPLAY 0.659574 (-3465 5885);
PAINT MONO (-3465 5885);
DISPLAY INVISIBLE (-3465 5885);
FORCEPROP 1 LASTPIN (-3475 5875) BN 2
J 0
(-3487 5883);
DISPLAY 0.489362 (-3487 5883);
PAINT GREEN (-3487 5883);
FORCEPROP 2 LAST CDS_LIB mstr_standard
J 0
(-3425 5875);
DISPLAY 0.723404 (-3425 5875);
PAINT MONO (-3425 5875);
DISPLAY INVISIBLE (-3425 5875);
FORCEPROP 1 LAST BODY_TYPE PLUMBING
J 0
(-3425 5925);
DISPLAY 0.872340 (-3425 5925);
PAINT GREEN (-3425 5925);
DISPLAY INVISIBLE (-3425 5925);
FORCEPROP 1 LAST HDL_TAP TRUE
J 0
(-3100 5750);
DISPLAY 0.872340 (-3100 5750);
DISPLAY INVISIBLE (-3100 5750);
FORCEPROP 1 LAST PATH I164
J 0
(-3427 5875);
DISPLAY 0.872340 (-3427 5875);
PAINT GREEN (-3427 5875);
DISPLAY INVISIBLE (-3427 5875);
FORCEADD TAP..1
(-3425 5825);
FORCEPROP 3 LASTPIN (-3475 5825) SIG_NAME M_E_CPU1_SA_DQ<3>
J 0
(-3465 5835);
DISPLAY 0.659574 (-3465 5835);
PAINT MONO (-3465 5835);
DISPLAY INVISIBLE (-3465 5835);
FORCEPROP 1 LASTPIN (-3475 5825) BN 3
J 0
(-3487 5833);
DISPLAY 0.489362 (-3487 5833);
PAINT GREEN (-3487 5833);
FORCEPROP 2 LAST CDS_LIB mstr_standard
J 0
(-3425 5825);
DISPLAY 0.723404 (-3425 5825);
PAINT MONO (-3425 5825);
DISPLAY INVISIBLE (-3425 5825);
FORCEPROP 1 LAST BODY_TYPE PLUMBING
J 0
(-3425 5875);
DISPLAY 0.872340 (-3425 5875);
PAINT GREEN (-3425 5875);
DISPLAY INVISIBLE (-3425 5875);
FORCEPROP 1 LAST HDL_TAP TRUE
J 0
(-3100 5700);
DISPLAY 0.872340 (-3100 5700);
DISPLAY INVISIBLE (-3100 5700);
FORCEPROP 1 LAST PATH I165
J 0
(-3427 5825);
DISPLAY 0.872340 (-3427 5825);
PAINT GREEN (-3427 5825);
DISPLAY INVISIBLE (-3427 5825);
FORCEADD TAP..1
(-3425 5775);
FORCEPROP 3 LASTPIN (-3475 5775) SIG_NAME M_E_CPU1_SA_DQ<4>
J 0
(-3465 5785);
DISPLAY 0.659574 (-3465 5785);
PAINT MONO (-3465 5785);
DISPLAY INVISIBLE (-3465 5785);
FORCEPROP 1 LASTPIN (-3475 5775) BN 4
J 0
(-3487 5783);
DISPLAY 0.489362 (-3487 5783);
PAINT GREEN (-3487 5783);
FORCEPROP 2 LAST CDS_LIB mstr_standard
J 0
(-3425 5775);
DISPLAY 0.723404 (-3425 5775);
PAINT MONO (-3425 5775);
DISPLAY INVISIBLE (-3425 5775);
FORCEPROP 1 LAST BODY_TYPE PLUMBING
J 0
(-3425 5825);
DISPLAY 0.872340 (-3425 5825);
PAINT GREEN (-3425 5825);
DISPLAY INVISIBLE (-3425 5825);
FORCEPROP 1 LAST HDL_TAP TRUE
J 0
(-3100 5650);
DISPLAY 0.872340 (-3100 5650);
DISPLAY INVISIBLE (-3100 5650);
FORCEPROP 1 LAST PATH I166
J 0
(-3427 5775);
DISPLAY 0.872340 (-3427 5775);
PAINT GREEN (-3427 5775);
DISPLAY INVISIBLE (-3427 5775);
FORCEADD TAP..1
(-3425 5725);
FORCEPROP 3 LASTPIN (-3475 5725) SIG_NAME M_E_CPU1_SA_DQ<5>
J 0
(-3465 5735);
DISPLAY 0.659574 (-3465 5735);
PAINT MONO (-3465 5735);
DISPLAY INVISIBLE (-3465 5735);
FORCEPROP 1 LASTPIN (-3475 5725) BN 5
J 0
(-3487 5733);
DISPLAY 0.489362 (-3487 5733);
PAINT GREEN (-3487 5733);
FORCEPROP 2 LAST CDS_LIB mstr_standard
J 0
(-3425 5725);
DISPLAY 0.723404 (-3425 5725);
PAINT MONO (-3425 5725);
DISPLAY INVISIBLE (-3425 5725);
FORCEPROP 1 LAST BODY_TYPE PLUMBING
J 0
(-3425 5775);
DISPLAY 0.872340 (-3425 5775);
PAINT GREEN (-3425 5775);
DISPLAY INVISIBLE (-3425 5775);
FORCEPROP 1 LAST HDL_TAP TRUE
J 0
(-3100 5600);
DISPLAY 0.872340 (-3100 5600);
DISPLAY INVISIBLE (-3100 5600);
FORCEPROP 1 LAST PATH I167
J 0
(-3427 5725);
DISPLAY 0.872340 (-3427 5725);
PAINT GREEN (-3427 5725);
DISPLAY INVISIBLE (-3427 5725);
FORCEADD TAP..1
(-3425 5675);
FORCEPROP 3 LASTPIN (-3475 5675) SIG_NAME M_E_CPU1_SA_DQ<6>
J 0
(-3465 5685);
DISPLAY 0.659574 (-3465 5685);
PAINT MONO (-3465 5685);
DISPLAY INVISIBLE (-3465 5685);
FORCEPROP 1 LASTPIN (-3475 5675) BN 6
J 0
(-3487 5683);
DISPLAY 0.489362 (-3487 5683);
PAINT GREEN (-3487 5683);
FORCEPROP 2 LAST CDS_LIB mstr_standard
J 0
(-3425 5675);
DISPLAY 0.723404 (-3425 5675);
PAINT MONO (-3425 5675);
DISPLAY INVISIBLE (-3425 5675);
FORCEPROP 1 LAST BODY_TYPE PLUMBING
J 0
(-3425 5725);
DISPLAY 0.872340 (-3425 5725);
PAINT GREEN (-3425 5725);
DISPLAY INVISIBLE (-3425 5725);
FORCEPROP 1 LAST HDL_TAP TRUE
J 0
(-3100 5550);
DISPLAY 0.872340 (-3100 5550);
DISPLAY INVISIBLE (-3100 5550);
FORCEPROP 1 LAST PATH I168
J 0
(-3427 5675);
DISPLAY 0.872340 (-3427 5675);
PAINT GREEN (-3427 5675);
DISPLAY INVISIBLE (-3427 5675);
FORCEADD TAP..1
(-3425 5625);
FORCEPROP 3 LASTPIN (-3475 5625) SIG_NAME M_E_CPU1_SA_DQ<7>
J 0
(-3465 5635);
DISPLAY 0.659574 (-3465 5635);
PAINT MONO (-3465 5635);
DISPLAY INVISIBLE (-3465 5635);
FORCEPROP 1 LASTPIN (-3475 5625) BN 7
J 0
(-3487 5633);
DISPLAY 0.489362 (-3487 5633);
PAINT GREEN (-3487 5633);
FORCEPROP 2 LAST CDS_LIB mstr_standard
J 0
(-3425 5625);
DISPLAY 0.723404 (-3425 5625);
PAINT MONO (-3425 5625);
DISPLAY INVISIBLE (-3425 5625);
FORCEPROP 1 LAST BODY_TYPE PLUMBING
J 0
(-3425 5675);
DISPLAY 0.872340 (-3425 5675);
PAINT GREEN (-3425 5675);
DISPLAY INVISIBLE (-3425 5675);
FORCEPROP 1 LAST HDL_TAP TRUE
J 0
(-3100 5500);
DISPLAY 0.872340 (-3100 5500);
DISPLAY INVISIBLE (-3100 5500);
FORCEPROP 1 LAST PATH I169
J 0
(-3427 5625);
DISPLAY 0.872340 (-3427 5625);
PAINT GREEN (-3427 5625);
DISPLAY INVISIBLE (-3427 5625);
FORCEADD TAP..1
(-3425 5525);
FORCEPROP 3 LASTPIN (-3475 5525) SIG_NAME M_E_CPU1_SA_DQ<8>
J 0
(-3465 5535);
DISPLAY 0.659574 (-3465 5535);
PAINT MONO (-3465 5535);
DISPLAY INVISIBLE (-3465 5535);
FORCEPROP 1 LASTPIN (-3475 5525) BN 8
J 0
(-3487 5533);
DISPLAY 0.489362 (-3487 5533);
PAINT GREEN (-3487 5533);
FORCEPROP 2 LAST CDS_LIB mstr_standard
J 0
(-3425 5525);
DISPLAY 0.723404 (-3425 5525);
PAINT MONO (-3425 5525);
DISPLAY INVISIBLE (-3425 5525);
FORCEPROP 1 LAST BODY_TYPE PLUMBING
J 0
(-3425 5575);
DISPLAY 0.872340 (-3425 5575);
PAINT GREEN (-3425 5575);
DISPLAY INVISIBLE (-3425 5575);
FORCEPROP 1 LAST HDL_TAP TRUE
J 0
(-3100 5400);
DISPLAY 0.872340 (-3100 5400);
DISPLAY INVISIBLE (-3100 5400);
FORCEPROP 1 LAST PATH I170
J 0
(-3427 5525);
DISPLAY 0.872340 (-3427 5525);
PAINT GREEN (-3427 5525);
DISPLAY INVISIBLE (-3427 5525);
FORCEADD TAP..1
(-3425 5475);
FORCEPROP 3 LASTPIN (-3475 5475) SIG_NAME M_E_CPU1_SA_DQ<9>
J 0
(-3465 5485);
DISPLAY 0.659574 (-3465 5485);
PAINT MONO (-3465 5485);
DISPLAY INVISIBLE (-3465 5485);
FORCEPROP 1 LASTPIN (-3475 5475) BN 9
J 0
(-3487 5483);
DISPLAY 0.489362 (-3487 5483);
PAINT GREEN (-3487 5483);
FORCEPROP 2 LAST CDS_LIB mstr_standard
J 0
(-3425 5475);
DISPLAY 0.723404 (-3425 5475);
PAINT MONO (-3425 5475);
DISPLAY INVISIBLE (-3425 5475);
FORCEPROP 1 LAST BODY_TYPE PLUMBING
J 0
(-3425 5525);
DISPLAY 0.872340 (-3425 5525);
PAINT GREEN (-3425 5525);
DISPLAY INVISIBLE (-3425 5525);
FORCEPROP 1 LAST HDL_TAP TRUE
J 0
(-3100 5350);
DISPLAY 0.872340 (-3100 5350);
DISPLAY INVISIBLE (-3100 5350);
FORCEPROP 1 LAST PATH I171
J 0
(-3427 5475);
DISPLAY 0.872340 (-3427 5475);
PAINT GREEN (-3427 5475);
DISPLAY INVISIBLE (-3427 5475);
FORCEADD TAP..1
(-3425 5425);
FORCEPROP 3 LASTPIN (-3475 5425) SIG_NAME M_E_CPU1_SA_DQ<10>
J 0
(-3465 5435);
DISPLAY 0.659574 (-3465 5435);
PAINT MONO (-3465 5435);
DISPLAY INVISIBLE (-3465 5435);
FORCEPROP 1 LASTPIN (-3475 5425) BN 10
J 0
(-3487 5433);
DISPLAY 0.489362 (-3487 5433);
PAINT GREEN (-3487 5433);
FORCEPROP 2 LAST CDS_LIB mstr_standard
J 0
(-3425 5425);
DISPLAY 0.723404 (-3425 5425);
PAINT MONO (-3425 5425);
DISPLAY INVISIBLE (-3425 5425);
FORCEPROP 1 LAST BODY_TYPE PLUMBING
J 0
(-3425 5475);
DISPLAY 0.872340 (-3425 5475);
PAINT GREEN (-3425 5475);
DISPLAY INVISIBLE (-3425 5475);
FORCEPROP 1 LAST HDL_TAP TRUE
J 0
(-3100 5300);
DISPLAY 0.872340 (-3100 5300);
DISPLAY INVISIBLE (-3100 5300);
FORCEPROP 1 LAST PATH I172
J 0
(-3427 5425);
DISPLAY 0.872340 (-3427 5425);
PAINT GREEN (-3427 5425);
DISPLAY INVISIBLE (-3427 5425);
FORCEADD TAP..1
(-3425 5375);
FORCEPROP 3 LASTPIN (-3475 5375) SIG_NAME M_E_CPU1_SA_DQ<11>
J 0
(-3465 5385);
DISPLAY 0.659574 (-3465 5385);
PAINT MONO (-3465 5385);
DISPLAY INVISIBLE (-3465 5385);
FORCEPROP 1 LASTPIN (-3475 5375) BN 11
J 0
(-3487 5383);
DISPLAY 0.489362 (-3487 5383);
PAINT GREEN (-3487 5383);
FORCEPROP 2 LAST CDS_LIB mstr_standard
J 0
(-3425 5375);
DISPLAY 0.723404 (-3425 5375);
PAINT MONO (-3425 5375);
DISPLAY INVISIBLE (-3425 5375);
FORCEPROP 1 LAST BODY_TYPE PLUMBING
J 0
(-3425 5425);
DISPLAY 0.872340 (-3425 5425);
PAINT GREEN (-3425 5425);
DISPLAY INVISIBLE (-3425 5425);
FORCEPROP 1 LAST HDL_TAP TRUE
J 0
(-3100 5250);
DISPLAY 0.872340 (-3100 5250);
DISPLAY INVISIBLE (-3100 5250);
FORCEPROP 1 LAST PATH I173
J 0
(-3427 5375);
DISPLAY 0.872340 (-3427 5375);
PAINT GREEN (-3427 5375);
DISPLAY INVISIBLE (-3427 5375);
FORCEADD TAP..1
(-3425 5325);
FORCEPROP 3 LASTPIN (-3475 5325) SIG_NAME M_E_CPU1_SA_DQ<12>
J 0
(-3465 5335);
DISPLAY 0.659574 (-3465 5335);
PAINT MONO (-3465 5335);
DISPLAY INVISIBLE (-3465 5335);
FORCEPROP 1 LASTPIN (-3475 5325) BN 12
J 0
(-3487 5333);
DISPLAY 0.489362 (-3487 5333);
PAINT GREEN (-3487 5333);
FORCEPROP 2 LAST CDS_LIB mstr_standard
J 0
(-3425 5325);
DISPLAY 0.723404 (-3425 5325);
PAINT MONO (-3425 5325);
DISPLAY INVISIBLE (-3425 5325);
FORCEPROP 1 LAST BODY_TYPE PLUMBING
J 0
(-3425 5375);
DISPLAY 0.872340 (-3425 5375);
PAINT GREEN (-3425 5375);
DISPLAY INVISIBLE (-3425 5375);
FORCEPROP 1 LAST HDL_TAP TRUE
J 0
(-3100 5200);
DISPLAY 0.872340 (-3100 5200);
DISPLAY INVISIBLE (-3100 5200);
FORCEPROP 1 LAST PATH I174
J 0
(-3427 5325);
DISPLAY 0.872340 (-3427 5325);
PAINT GREEN (-3427 5325);
DISPLAY INVISIBLE (-3427 5325);
FORCEADD TAP..1
(-3425 5275);
FORCEPROP 3 LASTPIN (-3475 5275) SIG_NAME M_E_CPU1_SA_DQ<13>
J 0
(-3465 5285);
DISPLAY 0.659574 (-3465 5285);
PAINT MONO (-3465 5285);
DISPLAY INVISIBLE (-3465 5285);
FORCEPROP 1 LASTPIN (-3475 5275) BN 13
J 0
(-3487 5283);
DISPLAY 0.489362 (-3487 5283);
PAINT GREEN (-3487 5283);
FORCEPROP 2 LAST CDS_LIB mstr_standard
J 0
(-3425 5275);
DISPLAY 0.723404 (-3425 5275);
PAINT MONO (-3425 5275);
DISPLAY INVISIBLE (-3425 5275);
FORCEPROP 1 LAST BODY_TYPE PLUMBING
J 0
(-3425 5325);
DISPLAY 0.872340 (-3425 5325);
PAINT GREEN (-3425 5325);
DISPLAY INVISIBLE (-3425 5325);
FORCEPROP 1 LAST HDL_TAP TRUE
J 0
(-3100 5150);
DISPLAY 0.872340 (-3100 5150);
DISPLAY INVISIBLE (-3100 5150);
FORCEPROP 1 LAST PATH I175
J 0
(-3427 5275);
DISPLAY 0.872340 (-3427 5275);
PAINT GREEN (-3427 5275);
DISPLAY INVISIBLE (-3427 5275);
FORCEADD TAP..1
(-3425 5225);
FORCEPROP 3 LASTPIN (-3475 5225) SIG_NAME M_E_CPU1_SA_DQ<14>
J 0
(-3465 5235);
DISPLAY 0.659574 (-3465 5235);
PAINT MONO (-3465 5235);
DISPLAY INVISIBLE (-3465 5235);
FORCEPROP 1 LASTPIN (-3475 5225) BN 14
J 0
(-3487 5233);
DISPLAY 0.489362 (-3487 5233);
PAINT GREEN (-3487 5233);
FORCEPROP 2 LAST CDS_LIB mstr_standard
J 0
(-3425 5225);
DISPLAY 0.723404 (-3425 5225);
PAINT MONO (-3425 5225);
DISPLAY INVISIBLE (-3425 5225);
FORCEPROP 1 LAST BODY_TYPE PLUMBING
J 0
(-3425 5275);
DISPLAY 0.872340 (-3425 5275);
PAINT GREEN (-3425 5275);
DISPLAY INVISIBLE (-3425 5275);
FORCEPROP 1 LAST HDL_TAP TRUE
J 0
(-3100 5100);
DISPLAY 0.872340 (-3100 5100);
DISPLAY INVISIBLE (-3100 5100);
FORCEPROP 1 LAST PATH I176
J 0
(-3427 5225);
DISPLAY 0.872340 (-3427 5225);
PAINT GREEN (-3427 5225);
DISPLAY INVISIBLE (-3427 5225);
FORCEADD TAP..1
(-3425 5175);
FORCEPROP 3 LASTPIN (-3475 5175) SIG_NAME M_E_CPU1_SA_DQ<15>
J 0
(-3465 5185);
DISPLAY 0.659574 (-3465 5185);
PAINT MONO (-3465 5185);
DISPLAY INVISIBLE (-3465 5185);
FORCEPROP 1 LASTPIN (-3475 5175) BN 15
J 0
(-3487 5183);
DISPLAY 0.489362 (-3487 5183);
PAINT GREEN (-3487 5183);
FORCEPROP 2 LAST CDS_LIB mstr_standard
J 0
(-3425 5175);
DISPLAY 0.723404 (-3425 5175);
PAINT MONO (-3425 5175);
DISPLAY INVISIBLE (-3425 5175);
FORCEPROP 1 LAST BODY_TYPE PLUMBING
J 0
(-3425 5225);
DISPLAY 0.872340 (-3425 5225);
PAINT GREEN (-3425 5225);
DISPLAY INVISIBLE (-3425 5225);
FORCEPROP 1 LAST HDL_TAP TRUE
J 0
(-3100 5050);
DISPLAY 0.872340 (-3100 5050);
DISPLAY INVISIBLE (-3100 5050);
FORCEPROP 1 LAST PATH I177
J 0
(-3427 5175);
DISPLAY 0.872340 (-3427 5175);
PAINT GREEN (-3427 5175);
DISPLAY INVISIBLE (-3427 5175);
FORCEADD TAP..1
(-3425 5075);
FORCEPROP 3 LASTPIN (-3475 5075) SIG_NAME M_E_CPU1_SA_DQ<16>
J 0
(-3465 5085);
DISPLAY 0.659574 (-3465 5085);
PAINT MONO (-3465 5085);
DISPLAY INVISIBLE (-3465 5085);
FORCEPROP 1 LASTPIN (-3475 5075) BN 16
J 0
(-3487 5083);
DISPLAY 0.489362 (-3487 5083);
PAINT GREEN (-3487 5083);
FORCEPROP 2 LAST CDS_LIB mstr_standard
J 0
(-3425 5075);
DISPLAY 0.723404 (-3425 5075);
PAINT MONO (-3425 5075);
DISPLAY INVISIBLE (-3425 5075);
FORCEPROP 1 LAST BODY_TYPE PLUMBING
J 0
(-3425 5125);
DISPLAY 0.872340 (-3425 5125);
PAINT GREEN (-3425 5125);
DISPLAY INVISIBLE (-3425 5125);
FORCEPROP 1 LAST HDL_TAP TRUE
J 0
(-3100 4950);
DISPLAY 0.872340 (-3100 4950);
DISPLAY INVISIBLE (-3100 4950);
FORCEPROP 1 LAST PATH I178
J 0
(-3427 5075);
DISPLAY 0.872340 (-3427 5075);
PAINT GREEN (-3427 5075);
DISPLAY INVISIBLE (-3427 5075);
FORCEADD TAP..1
(-3425 5025);
FORCEPROP 3 LASTPIN (-3475 5025) SIG_NAME M_E_CPU1_SA_DQ<17>
J 0
(-3465 5035);
DISPLAY 0.659574 (-3465 5035);
PAINT MONO (-3465 5035);
DISPLAY INVISIBLE (-3465 5035);
FORCEPROP 1 LASTPIN (-3475 5025) BN 17
J 0
(-3487 5033);
DISPLAY 0.489362 (-3487 5033);
PAINT GREEN (-3487 5033);
FORCEPROP 2 LAST CDS_LIB mstr_standard
J 0
(-3425 5025);
DISPLAY 0.723404 (-3425 5025);
PAINT MONO (-3425 5025);
DISPLAY INVISIBLE (-3425 5025);
FORCEPROP 1 LAST BODY_TYPE PLUMBING
J 0
(-3425 5075);
DISPLAY 0.872340 (-3425 5075);
PAINT GREEN (-3425 5075);
DISPLAY INVISIBLE (-3425 5075);
FORCEPROP 1 LAST HDL_TAP TRUE
J 0
(-3100 4900);
DISPLAY 0.872340 (-3100 4900);
DISPLAY INVISIBLE (-3100 4900);
FORCEPROP 1 LAST PATH I179
J 0
(-3427 5025);
DISPLAY 0.872340 (-3427 5025);
PAINT GREEN (-3427 5025);
DISPLAY INVISIBLE (-3427 5025);
FORCEADD TAP..1
(-3425 4975);
FORCEPROP 3 LASTPIN (-3475 4975) SIG_NAME M_E_CPU1_SA_DQ<18>
J 0
(-3465 4985);
DISPLAY 0.659574 (-3465 4985);
PAINT MONO (-3465 4985);
DISPLAY INVISIBLE (-3465 4985);
FORCEPROP 1 LASTPIN (-3475 4975) BN 18
J 0
(-3487 4983);
DISPLAY 0.489362 (-3487 4983);
PAINT GREEN (-3487 4983);
FORCEPROP 2 LAST CDS_LIB mstr_standard
J 0
(-3425 4975);
DISPLAY 0.723404 (-3425 4975);
PAINT MONO (-3425 4975);
DISPLAY INVISIBLE (-3425 4975);
FORCEPROP 1 LAST BODY_TYPE PLUMBING
J 0
(-3425 5025);
DISPLAY 0.872340 (-3425 5025);
PAINT GREEN (-3425 5025);
DISPLAY INVISIBLE (-3425 5025);
FORCEPROP 1 LAST HDL_TAP TRUE
J 0
(-3100 4850);
DISPLAY 0.872340 (-3100 4850);
DISPLAY INVISIBLE (-3100 4850);
FORCEPROP 1 LAST PATH I180
J 0
(-3427 4975);
DISPLAY 0.872340 (-3427 4975);
PAINT GREEN (-3427 4975);
DISPLAY INVISIBLE (-3427 4975);
FORCEADD TAP..1
(-3425 4875);
FORCEPROP 3 LASTPIN (-3475 4875) SIG_NAME M_E_CPU1_SA_DQ<20>
J 0
(-3465 4885);
DISPLAY 0.659574 (-3465 4885);
PAINT MONO (-3465 4885);
DISPLAY INVISIBLE (-3465 4885);
FORCEPROP 1 LASTPIN (-3475 4875) BN 20
J 0
(-3487 4883);
DISPLAY 0.489362 (-3487 4883);
PAINT GREEN (-3487 4883);
FORCEPROP 2 LAST CDS_LIB mstr_standard
J 0
(-3425 4875);
DISPLAY 0.723404 (-3425 4875);
PAINT MONO (-3425 4875);
DISPLAY INVISIBLE (-3425 4875);
FORCEPROP 1 LAST BODY_TYPE PLUMBING
J 0
(-3425 4925);
DISPLAY 0.872340 (-3425 4925);
PAINT GREEN (-3425 4925);
DISPLAY INVISIBLE (-3425 4925);
FORCEPROP 1 LAST HDL_TAP TRUE
J 0
(-3100 4750);
DISPLAY 0.872340 (-3100 4750);
DISPLAY INVISIBLE (-3100 4750);
FORCEPROP 1 LAST PATH I181
J 0
(-3427 4875);
DISPLAY 0.872340 (-3427 4875);
PAINT GREEN (-3427 4875);
DISPLAY INVISIBLE (-3427 4875);
FORCEADD TAP..1
(-3425 4925);
FORCEPROP 3 LASTPIN (-3475 4925) SIG_NAME M_E_CPU1_SA_DQ<19>
J 0
(-3465 4935);
DISPLAY 0.659574 (-3465 4935);
PAINT MONO (-3465 4935);
DISPLAY INVISIBLE (-3465 4935);
FORCEPROP 1 LASTPIN (-3475 4925) BN 19
J 0
(-3487 4933);
DISPLAY 0.489362 (-3487 4933);
PAINT GREEN (-3487 4933);
FORCEPROP 2 LAST CDS_LIB mstr_standard
J 0
(-3425 4925);
DISPLAY 0.723404 (-3425 4925);
PAINT MONO (-3425 4925);
DISPLAY INVISIBLE (-3425 4925);
FORCEPROP 1 LAST BODY_TYPE PLUMBING
J 0
(-3425 4975);
DISPLAY 0.872340 (-3425 4975);
PAINT GREEN (-3425 4975);
DISPLAY INVISIBLE (-3425 4975);
FORCEPROP 1 LAST HDL_TAP TRUE
J 0
(-3100 4800);
DISPLAY 0.872340 (-3100 4800);
DISPLAY INVISIBLE (-3100 4800);
FORCEPROP 1 LAST PATH I182
J 0
(-3427 4925);
DISPLAY 0.872340 (-3427 4925);
PAINT GREEN (-3427 4925);
DISPLAY INVISIBLE (-3427 4925);
FORCEADD TAP..1
(-3425 4825);
FORCEPROP 3 LASTPIN (-3475 4825) SIG_NAME M_E_CPU1_SA_DQ<21>
J 0
(-3465 4835);
DISPLAY 0.659574 (-3465 4835);
PAINT MONO (-3465 4835);
DISPLAY INVISIBLE (-3465 4835);
FORCEPROP 1 LASTPIN (-3475 4825) BN 21
J 0
(-3487 4833);
DISPLAY 0.489362 (-3487 4833);
PAINT GREEN (-3487 4833);
FORCEPROP 2 LAST CDS_LIB mstr_standard
J 0
(-3425 4825);
DISPLAY 0.723404 (-3425 4825);
PAINT MONO (-3425 4825);
DISPLAY INVISIBLE (-3425 4825);
FORCEPROP 1 LAST BODY_TYPE PLUMBING
J 0
(-3425 4875);
DISPLAY 0.872340 (-3425 4875);
PAINT GREEN (-3425 4875);
DISPLAY INVISIBLE (-3425 4875);
FORCEPROP 1 LAST HDL_TAP TRUE
J 0
(-3100 4700);
DISPLAY 0.872340 (-3100 4700);
DISPLAY INVISIBLE (-3100 4700);
FORCEPROP 1 LAST PATH I183
J 0
(-3427 4825);
DISPLAY 0.872340 (-3427 4825);
PAINT GREEN (-3427 4825);
DISPLAY INVISIBLE (-3427 4825);
FORCEADD TAP..1
(-3425 4775);
FORCEPROP 3 LASTPIN (-3475 4775) SIG_NAME M_E_CPU1_SA_DQ<22>
J 0
(-3465 4785);
DISPLAY 0.659574 (-3465 4785);
PAINT MONO (-3465 4785);
DISPLAY INVISIBLE (-3465 4785);
FORCEPROP 1 LASTPIN (-3475 4775) BN 22
J 0
(-3487 4783);
DISPLAY 0.489362 (-3487 4783);
PAINT GREEN (-3487 4783);
FORCEPROP 2 LAST CDS_LIB mstr_standard
J 0
(-3425 4775);
DISPLAY 0.723404 (-3425 4775);
PAINT MONO (-3425 4775);
DISPLAY INVISIBLE (-3425 4775);
FORCEPROP 1 LAST BODY_TYPE PLUMBING
J 0
(-3425 4825);
DISPLAY 0.872340 (-3425 4825);
PAINT GREEN (-3425 4825);
DISPLAY INVISIBLE (-3425 4825);
FORCEPROP 1 LAST HDL_TAP TRUE
J 0
(-3100 4650);
DISPLAY 0.872340 (-3100 4650);
DISPLAY INVISIBLE (-3100 4650);
FORCEPROP 1 LAST PATH I184
J 0
(-3427 4775);
DISPLAY 0.872340 (-3427 4775);
PAINT GREEN (-3427 4775);
DISPLAY INVISIBLE (-3427 4775);
FORCEADD TAP..1
(-3425 4725);
FORCEPROP 3 LASTPIN (-3475 4725) SIG_NAME M_E_CPU1_SA_DQ<23>
J 0
(-3465 4735);
DISPLAY 0.659574 (-3465 4735);
PAINT MONO (-3465 4735);
DISPLAY INVISIBLE (-3465 4735);
FORCEPROP 1 LASTPIN (-3475 4725) BN 23
J 0
(-3487 4733);
DISPLAY 0.489362 (-3487 4733);
PAINT GREEN (-3487 4733);
FORCEPROP 2 LAST CDS_LIB mstr_standard
J 0
(-3425 4725);
DISPLAY 0.723404 (-3425 4725);
PAINT MONO (-3425 4725);
DISPLAY INVISIBLE (-3425 4725);
FORCEPROP 1 LAST BODY_TYPE PLUMBING
J 0
(-3425 4775);
DISPLAY 0.872340 (-3425 4775);
PAINT GREEN (-3425 4775);
DISPLAY INVISIBLE (-3425 4775);
FORCEPROP 1 LAST HDL_TAP TRUE
J 0
(-3100 4600);
DISPLAY 0.872340 (-3100 4600);
DISPLAY INVISIBLE (-3100 4600);
FORCEPROP 1 LAST PATH I185
J 0
(-3427 4725);
DISPLAY 0.872340 (-3427 4725);
PAINT GREEN (-3427 4725);
DISPLAY INVISIBLE (-3427 4725);
FORCEADD TAP..1
(-3425 4625);
FORCEPROP 3 LASTPIN (-3475 4625) SIG_NAME M_E_CPU1_SA_DQ<24>
J 0
(-3465 4635);
DISPLAY 0.659574 (-3465 4635);
PAINT MONO (-3465 4635);
DISPLAY INVISIBLE (-3465 4635);
FORCEPROP 1 LASTPIN (-3475 4625) BN 24
J 0
(-3487 4633);
DISPLAY 0.489362 (-3487 4633);
PAINT GREEN (-3487 4633);
FORCEPROP 2 LAST CDS_LIB mstr_standard
J 0
(-3425 4625);
DISPLAY 0.723404 (-3425 4625);
PAINT MONO (-3425 4625);
DISPLAY INVISIBLE (-3425 4625);
FORCEPROP 1 LAST BODY_TYPE PLUMBING
J 0
(-3425 4675);
DISPLAY 0.872340 (-3425 4675);
PAINT GREEN (-3425 4675);
DISPLAY INVISIBLE (-3425 4675);
FORCEPROP 1 LAST HDL_TAP TRUE
J 0
(-3100 4500);
DISPLAY 0.872340 (-3100 4500);
DISPLAY INVISIBLE (-3100 4500);
FORCEPROP 1 LAST PATH I186
J 0
(-3427 4625);
DISPLAY 0.872340 (-3427 4625);
PAINT GREEN (-3427 4625);
DISPLAY INVISIBLE (-3427 4625);
FORCEADD TAP..1
(-3425 4575);
FORCEPROP 3 LASTPIN (-3475 4575) SIG_NAME M_E_CPU1_SA_DQ<25>
J 0
(-3465 4585);
DISPLAY 0.659574 (-3465 4585);
PAINT MONO (-3465 4585);
DISPLAY INVISIBLE (-3465 4585);
FORCEPROP 1 LASTPIN (-3475 4575) BN 25
J 0
(-3487 4583);
DISPLAY 0.489362 (-3487 4583);
PAINT GREEN (-3487 4583);
FORCEPROP 2 LAST CDS_LIB mstr_standard
J 0
(-3425 4575);
DISPLAY 0.723404 (-3425 4575);
PAINT MONO (-3425 4575);
DISPLAY INVISIBLE (-3425 4575);
FORCEPROP 1 LAST BODY_TYPE PLUMBING
J 0
(-3425 4625);
DISPLAY 0.872340 (-3425 4625);
PAINT GREEN (-3425 4625);
DISPLAY INVISIBLE (-3425 4625);
FORCEPROP 1 LAST HDL_TAP TRUE
J 0
(-3100 4450);
DISPLAY 0.872340 (-3100 4450);
DISPLAY INVISIBLE (-3100 4450);
FORCEPROP 1 LAST PATH I187
J 0
(-3427 4575);
DISPLAY 0.872340 (-3427 4575);
PAINT GREEN (-3427 4575);
DISPLAY INVISIBLE (-3427 4575);
FORCEADD TAP..1
(-3425 4525);
FORCEPROP 3 LASTPIN (-3475 4525) SIG_NAME M_E_CPU1_SA_DQ<26>
J 0
(-3465 4535);
DISPLAY 0.659574 (-3465 4535);
PAINT MONO (-3465 4535);
DISPLAY INVISIBLE (-3465 4535);
FORCEPROP 1 LASTPIN (-3475 4525) BN 26
J 0
(-3487 4533);
DISPLAY 0.489362 (-3487 4533);
PAINT GREEN (-3487 4533);
FORCEPROP 2 LAST CDS_LIB mstr_standard
J 0
(-3425 4525);
DISPLAY 0.723404 (-3425 4525);
PAINT MONO (-3425 4525);
DISPLAY INVISIBLE (-3425 4525);
FORCEPROP 1 LAST BODY_TYPE PLUMBING
J 0
(-3425 4575);
DISPLAY 0.872340 (-3425 4575);
PAINT GREEN (-3425 4575);
DISPLAY INVISIBLE (-3425 4575);
FORCEPROP 1 LAST HDL_TAP TRUE
J 0
(-3100 4400);
DISPLAY 0.872340 (-3100 4400);
DISPLAY INVISIBLE (-3100 4400);
FORCEPROP 1 LAST PATH I188
J 0
(-3427 4525);
DISPLAY 0.872340 (-3427 4525);
PAINT GREEN (-3427 4525);
DISPLAY INVISIBLE (-3427 4525);
FORCEADD TAP..1
(-3425 4425);
FORCEPROP 3 LASTPIN (-3475 4425) SIG_NAME M_E_CPU1_SA_DQ<28>
J 0
(-3465 4435);
DISPLAY 0.659574 (-3465 4435);
PAINT MONO (-3465 4435);
DISPLAY INVISIBLE (-3465 4435);
FORCEPROP 1 LASTPIN (-3475 4425) BN 28
J 0
(-3487 4433);
DISPLAY 0.489362 (-3487 4433);
PAINT GREEN (-3487 4433);
FORCEPROP 2 LAST CDS_LIB mstr_standard
J 0
(-3425 4425);
DISPLAY 0.723404 (-3425 4425);
PAINT MONO (-3425 4425);
DISPLAY INVISIBLE (-3425 4425);
FORCEPROP 1 LAST BODY_TYPE PLUMBING
J 0
(-3425 4475);
DISPLAY 0.872340 (-3425 4475);
PAINT GREEN (-3425 4475);
DISPLAY INVISIBLE (-3425 4475);
FORCEPROP 1 LAST HDL_TAP TRUE
J 0
(-3100 4300);
DISPLAY 0.872340 (-3100 4300);
DISPLAY INVISIBLE (-3100 4300);
FORCEPROP 1 LAST PATH I189
J 0
(-3427 4425);
DISPLAY 0.872340 (-3427 4425);
PAINT GREEN (-3427 4425);
DISPLAY INVISIBLE (-3427 4425);
FORCEADD TAP..1
(-3425 4475);
FORCEPROP 3 LASTPIN (-3475 4475) SIG_NAME M_E_CPU1_SA_DQ<27>
J 0
(-3465 4485);
DISPLAY 0.659574 (-3465 4485);
PAINT MONO (-3465 4485);
DISPLAY INVISIBLE (-3465 4485);
FORCEPROP 1 LASTPIN (-3475 4475) BN 27
J 0
(-3487 4483);
DISPLAY 0.489362 (-3487 4483);
PAINT GREEN (-3487 4483);
FORCEPROP 2 LAST CDS_LIB mstr_standard
J 0
(-3425 4475);
DISPLAY 0.723404 (-3425 4475);
PAINT MONO (-3425 4475);
DISPLAY INVISIBLE (-3425 4475);
FORCEPROP 1 LAST BODY_TYPE PLUMBING
J 0
(-3425 4525);
DISPLAY 0.872340 (-3425 4525);
PAINT GREEN (-3425 4525);
DISPLAY INVISIBLE (-3425 4525);
FORCEPROP 1 LAST HDL_TAP TRUE
J 0
(-3100 4350);
DISPLAY 0.872340 (-3100 4350);
DISPLAY INVISIBLE (-3100 4350);
FORCEPROP 1 LAST PATH I190
J 0
(-3427 4475);
DISPLAY 0.872340 (-3427 4475);
PAINT GREEN (-3427 4475);
DISPLAY INVISIBLE (-3427 4475);
FORCEADD TAP..1
(-3425 4375);
FORCEPROP 3 LASTPIN (-3475 4375) SIG_NAME M_E_CPU1_SA_DQ<29>
J 0
(-3465 4385);
DISPLAY 0.659574 (-3465 4385);
PAINT MONO (-3465 4385);
DISPLAY INVISIBLE (-3465 4385);
FORCEPROP 1 LASTPIN (-3475 4375) BN 29
J 0
(-3487 4383);
DISPLAY 0.489362 (-3487 4383);
PAINT GREEN (-3487 4383);
FORCEPROP 2 LAST CDS_LIB mstr_standard
J 0
(-3425 4375);
DISPLAY 0.723404 (-3425 4375);
PAINT MONO (-3425 4375);
DISPLAY INVISIBLE (-3425 4375);
FORCEPROP 1 LAST BODY_TYPE PLUMBING
J 0
(-3425 4425);
DISPLAY 0.872340 (-3425 4425);
PAINT GREEN (-3425 4425);
DISPLAY INVISIBLE (-3425 4425);
FORCEPROP 1 LAST HDL_TAP TRUE
J 0
(-3100 4250);
DISPLAY 0.872340 (-3100 4250);
DISPLAY INVISIBLE (-3100 4250);
FORCEPROP 1 LAST PATH I191
J 0
(-3427 4375);
DISPLAY 0.872340 (-3427 4375);
PAINT GREEN (-3427 4375);
DISPLAY INVISIBLE (-3427 4375);
FORCEADD TAP..1
(-3425 4325);
FORCEPROP 3 LASTPIN (-3475 4325) SIG_NAME M_E_CPU1_SA_DQ<30>
J 0
(-3465 4335);
DISPLAY 0.659574 (-3465 4335);
PAINT MONO (-3465 4335);
DISPLAY INVISIBLE (-3465 4335);
FORCEPROP 1 LASTPIN (-3475 4325) BN 30
J 0
(-3487 4333);
DISPLAY 0.489362 (-3487 4333);
PAINT GREEN (-3487 4333);
FORCEPROP 2 LAST CDS_LIB mstr_standard
J 0
(-3425 4325);
DISPLAY 0.723404 (-3425 4325);
PAINT MONO (-3425 4325);
DISPLAY INVISIBLE (-3425 4325);
FORCEPROP 1 LAST BODY_TYPE PLUMBING
J 0
(-3425 4375);
DISPLAY 0.872340 (-3425 4375);
PAINT GREEN (-3425 4375);
DISPLAY INVISIBLE (-3425 4375);
FORCEPROP 1 LAST HDL_TAP TRUE
J 0
(-3100 4200);
DISPLAY 0.872340 (-3100 4200);
DISPLAY INVISIBLE (-3100 4200);
FORCEPROP 1 LAST PATH I192
J 0
(-3427 4325);
DISPLAY 0.872340 (-3427 4325);
PAINT GREEN (-3427 4325);
DISPLAY INVISIBLE (-3427 4325);
FORCEADD TAP..1
(-3425 4275);
FORCEPROP 3 LASTPIN (-3475 4275) SIG_NAME M_E_CPU1_SA_DQ<31>
J 0
(-3465 4285);
DISPLAY 0.659574 (-3465 4285);
PAINT MONO (-3465 4285);
DISPLAY INVISIBLE (-3465 4285);
FORCEPROP 1 LASTPIN (-3475 4275) BN 31
J 0
(-3487 4283);
DISPLAY 0.489362 (-3487 4283);
PAINT GREEN (-3487 4283);
FORCEPROP 2 LAST CDS_LIB mstr_standard
J 0
(-3425 4275);
DISPLAY 0.723404 (-3425 4275);
PAINT MONO (-3425 4275);
DISPLAY INVISIBLE (-3425 4275);
FORCEPROP 1 LAST BODY_TYPE PLUMBING
J 0
(-3425 4325);
DISPLAY 0.872340 (-3425 4325);
PAINT GREEN (-3425 4325);
DISPLAY INVISIBLE (-3425 4325);
FORCEPROP 1 LAST HDL_TAP TRUE
J 0
(-3100 4150);
DISPLAY 0.872340 (-3100 4150);
DISPLAY INVISIBLE (-3100 4150);
FORCEPROP 1 LAST PATH I193
J 0
(-3427 4275);
DISPLAY 0.872340 (-3427 4275);
PAINT GREEN (-3427 4275);
DISPLAY INVISIBLE (-3427 4275);
FORCEADD TAP..1
(-3425 4175);
FORCEPROP 3 LASTPIN (-3475 4175) SIG_NAME M_E_CPU1_SB_DQ<0>
J 0
(-3465 4185);
DISPLAY 0.659574 (-3465 4185);
PAINT MONO (-3465 4185);
DISPLAY INVISIBLE (-3465 4185);
FORCEPROP 1 LASTPIN (-3475 4175) BN 0
J 0
(-3487 4183);
DISPLAY 0.489362 (-3487 4183);
PAINT GREEN (-3487 4183);
FORCEPROP 2 LAST CDS_LIB mstr_standard
J 0
(-3425 4175);
DISPLAY 0.723404 (-3425 4175);
PAINT MONO (-3425 4175);
DISPLAY INVISIBLE (-3425 4175);
FORCEPROP 1 LAST BODY_TYPE PLUMBING
J 0
(-3425 4225);
DISPLAY 0.872340 (-3425 4225);
PAINT GREEN (-3425 4225);
DISPLAY INVISIBLE (-3425 4225);
FORCEPROP 1 LAST HDL_TAP TRUE
J 0
(-3100 4050);
DISPLAY 0.872340 (-3100 4050);
DISPLAY INVISIBLE (-3100 4050);
FORCEPROP 1 LAST PATH I194
J 0
(-3427 4175);
DISPLAY 0.872340 (-3427 4175);
PAINT GREEN (-3427 4175);
DISPLAY INVISIBLE (-3427 4175);
FORCEADD TAP..1
(-3425 4125);
FORCEPROP 3 LASTPIN (-3475 4125) SIG_NAME M_E_CPU1_SB_DQ<1>
J 0
(-3465 4135);
DISPLAY 0.659574 (-3465 4135);
PAINT MONO (-3465 4135);
DISPLAY INVISIBLE (-3465 4135);
FORCEPROP 1 LASTPIN (-3475 4125) BN 1
J 0
(-3487 4133);
DISPLAY 0.489362 (-3487 4133);
PAINT GREEN (-3487 4133);
FORCEPROP 2 LAST CDS_LIB mstr_standard
J 0
(-3425 4125);
DISPLAY 0.723404 (-3425 4125);
PAINT MONO (-3425 4125);
DISPLAY INVISIBLE (-3425 4125);
FORCEPROP 1 LAST BODY_TYPE PLUMBING
J 0
(-3425 4175);
DISPLAY 0.872340 (-3425 4175);
PAINT GREEN (-3425 4175);
DISPLAY INVISIBLE (-3425 4175);
FORCEPROP 1 LAST HDL_TAP TRUE
J 0
(-3100 4000);
DISPLAY 0.872340 (-3100 4000);
DISPLAY INVISIBLE (-3100 4000);
FORCEPROP 1 LAST PATH I195
J 0
(-3427 4125);
DISPLAY 0.872340 (-3427 4125);
PAINT GREEN (-3427 4125);
DISPLAY INVISIBLE (-3427 4125);
FORCEADD OFFPAGE..6
R 2
(-2825 2425);
FORCEPROP 2 LAST $XR0 101 
J 0
(-2611 2425);
DISPLAY 0.638298 (-2611 2425);
PAINT MONO (-2611 2425);
FORCEPROP 2 LAST PATH I196
J 0
(-2600 2475);
DISPLAY 1.021277 (-2600 2475);
DISPLAY INVISIBLE (-2600 2475);
FORCEPROP 1 LAST COMMENT_BODY TRUE
J 2
(-2925 2350);
DISPLAY 0.872340 (-2925 2350);
PAINT GREEN (-2925 2350);
DISPLAY INVISIBLE (-2925 2350);
FORCEPROP 1 LAST OFFPAGE TRUE
J 2
(-3150 2300);
DISPLAY 0.872340 (-3150 2300);
PAINT GREEN (-3150 2300);
DISPLAY INVISIBLE (-3150 2300);
FORCEPROP 2 LAST CDS_LIB mstr_standard
J 2
(-2825 2425);
DISPLAY 0.723404 (-2825 2425);
PAINT MONO (-2825 2425);
DISPLAY INVISIBLE (-2825 2425);
FORCEADD TAP..1
(-3425 4075);
FORCEPROP 3 LASTPIN (-3475 4075) SIG_NAME M_E_CPU1_SB_DQ<2>
J 0
(-3465 4085);
DISPLAY 0.659574 (-3465 4085);
PAINT MONO (-3465 4085);
DISPLAY INVISIBLE (-3465 4085);
FORCEPROP 1 LASTPIN (-3475 4075) BN 2
J 0
(-3487 4083);
DISPLAY 0.489362 (-3487 4083);
PAINT GREEN (-3487 4083);
FORCEPROP 2 LAST CDS_LIB mstr_standard
J 0
(-3425 4075);
DISPLAY 0.723404 (-3425 4075);
PAINT MONO (-3425 4075);
DISPLAY INVISIBLE (-3425 4075);
FORCEPROP 1 LAST BODY_TYPE PLUMBING
J 0
(-3425 4125);
DISPLAY 0.872340 (-3425 4125);
PAINT GREEN (-3425 4125);
DISPLAY INVISIBLE (-3425 4125);
FORCEPROP 1 LAST HDL_TAP TRUE
J 0
(-3100 3950);
DISPLAY 0.872340 (-3100 3950);
DISPLAY INVISIBLE (-3100 3950);
FORCEPROP 1 LAST PATH I197
J 0
(-3427 4075);
DISPLAY 0.872340 (-3427 4075);
PAINT GREEN (-3427 4075);
DISPLAY INVISIBLE (-3427 4075);
FORCEADD TAP..1
(-3425 3975);
FORCEPROP 3 LASTPIN (-3475 3975) SIG_NAME M_E_CPU1_SB_DQ<4>
J 0
(-3465 3985);
DISPLAY 0.659574 (-3465 3985);
PAINT MONO (-3465 3985);
DISPLAY INVISIBLE (-3465 3985);
FORCEPROP 1 LASTPIN (-3475 3975) BN 4
J 0
(-3487 3983);
DISPLAY 0.489362 (-3487 3983);
PAINT GREEN (-3487 3983);
FORCEPROP 2 LAST CDS_LIB mstr_standard
J 0
(-3425 3975);
DISPLAY 0.723404 (-3425 3975);
PAINT MONO (-3425 3975);
DISPLAY INVISIBLE (-3425 3975);
FORCEPROP 1 LAST BODY_TYPE PLUMBING
J 0
(-3425 4025);
DISPLAY 0.872340 (-3425 4025);
PAINT GREEN (-3425 4025);
DISPLAY INVISIBLE (-3425 4025);
FORCEPROP 1 LAST HDL_TAP TRUE
J 0
(-3100 3850);
DISPLAY 0.872340 (-3100 3850);
DISPLAY INVISIBLE (-3100 3850);
FORCEPROP 1 LAST PATH I198
J 0
(-3427 3975);
DISPLAY 0.872340 (-3427 3975);
PAINT GREEN (-3427 3975);
DISPLAY INVISIBLE (-3427 3975);
FORCEADD TAP..1
(-3425 4025);
FORCEPROP 3 LASTPIN (-3475 4025) SIG_NAME M_E_CPU1_SB_DQ<3>
J 0
(-3465 4035);
DISPLAY 0.659574 (-3465 4035);
PAINT MONO (-3465 4035);
DISPLAY INVISIBLE (-3465 4035);
FORCEPROP 1 LASTPIN (-3475 4025) BN 3
J 0
(-3487 4033);
DISPLAY 0.489362 (-3487 4033);
PAINT GREEN (-3487 4033);
FORCEPROP 2 LAST CDS_LIB mstr_standard
J 0
(-3425 4025);
DISPLAY 0.723404 (-3425 4025);
PAINT MONO (-3425 4025);
DISPLAY INVISIBLE (-3425 4025);
FORCEPROP 1 LAST BODY_TYPE PLUMBING
J 0
(-3425 4075);
DISPLAY 0.872340 (-3425 4075);
PAINT GREEN (-3425 4075);
DISPLAY INVISIBLE (-3425 4075);
FORCEPROP 1 LAST HDL_TAP TRUE
J 0
(-3100 3900);
DISPLAY 0.872340 (-3100 3900);
DISPLAY INVISIBLE (-3100 3900);
FORCEPROP 1 LAST PATH I199
J 0
(-3427 4025);
DISPLAY 0.872340 (-3427 4025);
PAINT GREEN (-3427 4025);
DISPLAY INVISIBLE (-3427 4025);
FORCEADD TAP..1
(-3425 3925);
FORCEPROP 3 LASTPIN (-3475 3925) SIG_NAME M_E_CPU1_SB_DQ<5>
J 0
(-3465 3935);
DISPLAY 0.659574 (-3465 3935);
PAINT MONO (-3465 3935);
DISPLAY INVISIBLE (-3465 3935);
FORCEPROP 1 LASTPIN (-3475 3925) BN 5
J 0
(-3487 3933);
DISPLAY 0.489362 (-3487 3933);
PAINT GREEN (-3487 3933);
FORCEPROP 2 LAST CDS_LIB mstr_standard
J 0
(-3425 3925);
DISPLAY 0.723404 (-3425 3925);
PAINT MONO (-3425 3925);
DISPLAY INVISIBLE (-3425 3925);
FORCEPROP 1 LAST BODY_TYPE PLUMBING
J 0
(-3425 3975);
DISPLAY 0.872340 (-3425 3975);
PAINT GREEN (-3425 3975);
DISPLAY INVISIBLE (-3425 3975);
FORCEPROP 1 LAST HDL_TAP TRUE
J 0
(-3100 3800);
DISPLAY 0.872340 (-3100 3800);
DISPLAY INVISIBLE (-3100 3800);
FORCEPROP 1 LAST PATH I200
J 0
(-3427 3925);
DISPLAY 0.872340 (-3427 3925);
PAINT GREEN (-3427 3925);
DISPLAY INVISIBLE (-3427 3925);
FORCEADD TAP..1
(-3425 3875);
FORCEPROP 3 LASTPIN (-3475 3875) SIG_NAME M_E_CPU1_SB_DQ<6>
J 0
(-3465 3885);
DISPLAY 0.659574 (-3465 3885);
PAINT MONO (-3465 3885);
DISPLAY INVISIBLE (-3465 3885);
FORCEPROP 1 LASTPIN (-3475 3875) BN 6
J 0
(-3487 3883);
DISPLAY 0.489362 (-3487 3883);
PAINT GREEN (-3487 3883);
FORCEPROP 2 LAST CDS_LIB mstr_standard
J 0
(-3425 3875);
DISPLAY 0.723404 (-3425 3875);
PAINT MONO (-3425 3875);
DISPLAY INVISIBLE (-3425 3875);
FORCEPROP 1 LAST BODY_TYPE PLUMBING
J 0
(-3425 3925);
DISPLAY 0.872340 (-3425 3925);
PAINT GREEN (-3425 3925);
DISPLAY INVISIBLE (-3425 3925);
FORCEPROP 1 LAST HDL_TAP TRUE
J 0
(-3100 3750);
DISPLAY 0.872340 (-3100 3750);
DISPLAY INVISIBLE (-3100 3750);
FORCEPROP 1 LAST PATH I201
J 0
(-3427 3875);
DISPLAY 0.872340 (-3427 3875);
PAINT GREEN (-3427 3875);
DISPLAY INVISIBLE (-3427 3875);
FORCEADD TAP..1
(-3425 3825);
FORCEPROP 3 LASTPIN (-3475 3825) SIG_NAME M_E_CPU1_SB_DQ<7>
J 0
(-3465 3835);
DISPLAY 0.659574 (-3465 3835);
PAINT MONO (-3465 3835);
DISPLAY INVISIBLE (-3465 3835);
FORCEPROP 1 LASTPIN (-3475 3825) BN 7
J 0
(-3487 3833);
DISPLAY 0.489362 (-3487 3833);
PAINT GREEN (-3487 3833);
FORCEPROP 2 LAST CDS_LIB mstr_standard
J 0
(-3425 3825);
DISPLAY 0.723404 (-3425 3825);
PAINT MONO (-3425 3825);
DISPLAY INVISIBLE (-3425 3825);
FORCEPROP 1 LAST BODY_TYPE PLUMBING
J 0
(-3425 3875);
DISPLAY 0.872340 (-3425 3875);
PAINT GREEN (-3425 3875);
DISPLAY INVISIBLE (-3425 3875);
FORCEPROP 1 LAST HDL_TAP TRUE
J 0
(-3100 3700);
DISPLAY 0.872340 (-3100 3700);
DISPLAY INVISIBLE (-3100 3700);
FORCEPROP 1 LAST PATH I202
J 0
(-3427 3825);
DISPLAY 0.872340 (-3427 3825);
PAINT GREEN (-3427 3825);
DISPLAY INVISIBLE (-3427 3825);
FORCEADD TAP..1
(-3425 3725);
FORCEPROP 3 LASTPIN (-3475 3725) SIG_NAME M_E_CPU1_SB_DQ<8>
J 0
(-3465 3735);
DISPLAY 0.659574 (-3465 3735);
PAINT MONO (-3465 3735);
DISPLAY INVISIBLE (-3465 3735);
FORCEPROP 1 LASTPIN (-3475 3725) BN 8
J 0
(-3487 3733);
DISPLAY 0.489362 (-3487 3733);
PAINT GREEN (-3487 3733);
FORCEPROP 2 LAST CDS_LIB mstr_standard
J 0
(-3425 3725);
DISPLAY 0.723404 (-3425 3725);
PAINT MONO (-3425 3725);
DISPLAY INVISIBLE (-3425 3725);
FORCEPROP 1 LAST BODY_TYPE PLUMBING
J 0
(-3425 3775);
DISPLAY 0.872340 (-3425 3775);
PAINT GREEN (-3425 3775);
DISPLAY INVISIBLE (-3425 3775);
FORCEPROP 1 LAST HDL_TAP TRUE
J 0
(-3100 3600);
DISPLAY 0.872340 (-3100 3600);
DISPLAY INVISIBLE (-3100 3600);
FORCEPROP 1 LAST PATH I203
J 0
(-3427 3725);
DISPLAY 0.872340 (-3427 3725);
PAINT GREEN (-3427 3725);
DISPLAY INVISIBLE (-3427 3725);
FORCEADD TAP..1
(-3425 3675);
FORCEPROP 3 LASTPIN (-3475 3675) SIG_NAME M_E_CPU1_SB_DQ<9>
J 0
(-3465 3685);
DISPLAY 0.659574 (-3465 3685);
PAINT MONO (-3465 3685);
DISPLAY INVISIBLE (-3465 3685);
FORCEPROP 1 LASTPIN (-3475 3675) BN 9
J 0
(-3487 3683);
DISPLAY 0.489362 (-3487 3683);
PAINT GREEN (-3487 3683);
FORCEPROP 2 LAST CDS_LIB mstr_standard
J 0
(-3425 3675);
DISPLAY 0.723404 (-3425 3675);
PAINT MONO (-3425 3675);
DISPLAY INVISIBLE (-3425 3675);
FORCEPROP 1 LAST BODY_TYPE PLUMBING
J 0
(-3425 3725);
DISPLAY 0.872340 (-3425 3725);
PAINT GREEN (-3425 3725);
DISPLAY INVISIBLE (-3425 3725);
FORCEPROP 1 LAST HDL_TAP TRUE
J 0
(-3100 3550);
DISPLAY 0.872340 (-3100 3550);
DISPLAY INVISIBLE (-3100 3550);
FORCEPROP 1 LAST PATH I204
J 0
(-3427 3675);
DISPLAY 0.872340 (-3427 3675);
PAINT GREEN (-3427 3675);
DISPLAY INVISIBLE (-3427 3675);
FORCEADD TAP..1
(-3425 3625);
FORCEPROP 3 LASTPIN (-3475 3625) SIG_NAME M_E_CPU1_SB_DQ<10>
J 0
(-3465 3635);
DISPLAY 0.659574 (-3465 3635);
PAINT MONO (-3465 3635);
DISPLAY INVISIBLE (-3465 3635);
FORCEPROP 1 LASTPIN (-3475 3625) BN 10
J 0
(-3487 3633);
DISPLAY 0.489362 (-3487 3633);
PAINT GREEN (-3487 3633);
FORCEPROP 2 LAST CDS_LIB mstr_standard
J 0
(-3425 3625);
DISPLAY 0.723404 (-3425 3625);
PAINT MONO (-3425 3625);
DISPLAY INVISIBLE (-3425 3625);
FORCEPROP 1 LAST BODY_TYPE PLUMBING
J 0
(-3425 3675);
DISPLAY 0.872340 (-3425 3675);
PAINT GREEN (-3425 3675);
DISPLAY INVISIBLE (-3425 3675);
FORCEPROP 1 LAST HDL_TAP TRUE
J 0
(-3100 3500);
DISPLAY 0.872340 (-3100 3500);
DISPLAY INVISIBLE (-3100 3500);
FORCEPROP 1 LAST PATH I205
J 0
(-3427 3625);
DISPLAY 0.872340 (-3427 3625);
PAINT GREEN (-3427 3625);
DISPLAY INVISIBLE (-3427 3625);
FORCEADD TAP..1
(-3425 3575);
FORCEPROP 3 LASTPIN (-3475 3575) SIG_NAME M_E_CPU1_SB_DQ<11>
J 0
(-3465 3585);
DISPLAY 0.659574 (-3465 3585);
PAINT MONO (-3465 3585);
DISPLAY INVISIBLE (-3465 3585);
FORCEPROP 1 LASTPIN (-3475 3575) BN 11
J 0
(-3487 3583);
DISPLAY 0.489362 (-3487 3583);
PAINT GREEN (-3487 3583);
FORCEPROP 2 LAST CDS_LIB mstr_standard
J 0
(-3425 3575);
DISPLAY 0.723404 (-3425 3575);
PAINT MONO (-3425 3575);
DISPLAY INVISIBLE (-3425 3575);
FORCEPROP 1 LAST BODY_TYPE PLUMBING
J 0
(-3425 3625);
DISPLAY 0.872340 (-3425 3625);
PAINT GREEN (-3425 3625);
DISPLAY INVISIBLE (-3425 3625);
FORCEPROP 1 LAST HDL_TAP TRUE
J 0
(-3100 3450);
DISPLAY 0.872340 (-3100 3450);
DISPLAY INVISIBLE (-3100 3450);
FORCEPROP 1 LAST PATH I206
J 0
(-3427 3575);
DISPLAY 0.872340 (-3427 3575);
PAINT GREEN (-3427 3575);
DISPLAY INVISIBLE (-3427 3575);
FORCEADD TAP..1
(-3425 3525);
FORCEPROP 3 LASTPIN (-3475 3525) SIG_NAME M_E_CPU1_SB_DQ<12>
J 0
(-3465 3535);
DISPLAY 0.659574 (-3465 3535);
PAINT MONO (-3465 3535);
DISPLAY INVISIBLE (-3465 3535);
FORCEPROP 1 LASTPIN (-3475 3525) BN 12
J 0
(-3487 3533);
DISPLAY 0.489362 (-3487 3533);
PAINT GREEN (-3487 3533);
FORCEPROP 2 LAST CDS_LIB mstr_standard
J 0
(-3425 3525);
DISPLAY 0.723404 (-3425 3525);
PAINT MONO (-3425 3525);
DISPLAY INVISIBLE (-3425 3525);
FORCEPROP 1 LAST BODY_TYPE PLUMBING
J 0
(-3425 3575);
DISPLAY 0.872340 (-3425 3575);
PAINT GREEN (-3425 3575);
DISPLAY INVISIBLE (-3425 3575);
FORCEPROP 1 LAST HDL_TAP TRUE
J 0
(-3100 3400);
DISPLAY 0.872340 (-3100 3400);
DISPLAY INVISIBLE (-3100 3400);
FORCEPROP 1 LAST PATH I207
J 0
(-3427 3525);
DISPLAY 0.872340 (-3427 3525);
PAINT GREEN (-3427 3525);
DISPLAY INVISIBLE (-3427 3525);
FORCEADD TAP..1
(-3425 3475);
FORCEPROP 3 LASTPIN (-3475 3475) SIG_NAME M_E_CPU1_SB_DQ<13>
J 0
(-3465 3485);
DISPLAY 0.659574 (-3465 3485);
PAINT MONO (-3465 3485);
DISPLAY INVISIBLE (-3465 3485);
FORCEPROP 1 LASTPIN (-3475 3475) BN 13
J 0
(-3487 3483);
DISPLAY 0.489362 (-3487 3483);
PAINT GREEN (-3487 3483);
FORCEPROP 2 LAST CDS_LIB mstr_standard
J 0
(-3425 3475);
DISPLAY 0.723404 (-3425 3475);
PAINT MONO (-3425 3475);
DISPLAY INVISIBLE (-3425 3475);
FORCEPROP 1 LAST BODY_TYPE PLUMBING
J 0
(-3425 3525);
DISPLAY 0.872340 (-3425 3525);
PAINT GREEN (-3425 3525);
DISPLAY INVISIBLE (-3425 3525);
FORCEPROP 1 LAST HDL_TAP TRUE
J 0
(-3100 3350);
DISPLAY 0.872340 (-3100 3350);
DISPLAY INVISIBLE (-3100 3350);
FORCEPROP 1 LAST PATH I208
J 0
(-3427 3475);
DISPLAY 0.872340 (-3427 3475);
PAINT GREEN (-3427 3475);
DISPLAY INVISIBLE (-3427 3475);
FORCEADD TAP..1
(-3425 3425);
FORCEPROP 3 LASTPIN (-3475 3425) SIG_NAME M_E_CPU1_SB_DQ<14>
J 0
(-3465 3435);
DISPLAY 0.659574 (-3465 3435);
PAINT MONO (-3465 3435);
DISPLAY INVISIBLE (-3465 3435);
FORCEPROP 1 LASTPIN (-3475 3425) BN 14
J 0
(-3487 3433);
DISPLAY 0.489362 (-3487 3433);
PAINT GREEN (-3487 3433);
FORCEPROP 2 LAST CDS_LIB mstr_standard
J 0
(-3425 3425);
DISPLAY 0.723404 (-3425 3425);
PAINT MONO (-3425 3425);
DISPLAY INVISIBLE (-3425 3425);
FORCEPROP 1 LAST BODY_TYPE PLUMBING
J 0
(-3425 3475);
DISPLAY 0.872340 (-3425 3475);
PAINT GREEN (-3425 3475);
DISPLAY INVISIBLE (-3425 3475);
FORCEPROP 1 LAST HDL_TAP TRUE
J 0
(-3100 3300);
DISPLAY 0.872340 (-3100 3300);
DISPLAY INVISIBLE (-3100 3300);
FORCEPROP 1 LAST PATH I209
J 0
(-3427 3425);
DISPLAY 0.872340 (-3427 3425);
PAINT GREEN (-3427 3425);
DISPLAY INVISIBLE (-3427 3425);
FORCEADD TAP..1
(-3425 3375);
FORCEPROP 3 LASTPIN (-3475 3375) SIG_NAME M_E_CPU1_SB_DQ<15>
J 0
(-3465 3385);
DISPLAY 0.659574 (-3465 3385);
PAINT MONO (-3465 3385);
DISPLAY INVISIBLE (-3465 3385);
FORCEPROP 1 LASTPIN (-3475 3375) BN 15
J 0
(-3487 3383);
DISPLAY 0.489362 (-3487 3383);
PAINT GREEN (-3487 3383);
FORCEPROP 2 LAST CDS_LIB mstr_standard
J 0
(-3425 3375);
DISPLAY 0.723404 (-3425 3375);
PAINT MONO (-3425 3375);
DISPLAY INVISIBLE (-3425 3375);
FORCEPROP 1 LAST BODY_TYPE PLUMBING
J 0
(-3425 3425);
DISPLAY 0.872340 (-3425 3425);
PAINT GREEN (-3425 3425);
DISPLAY INVISIBLE (-3425 3425);
FORCEPROP 1 LAST HDL_TAP TRUE
J 0
(-3100 3250);
DISPLAY 0.872340 (-3100 3250);
DISPLAY INVISIBLE (-3100 3250);
FORCEPROP 1 LAST PATH I210
J 0
(-3427 3375);
DISPLAY 0.872340 (-3427 3375);
PAINT GREEN (-3427 3375);
DISPLAY INVISIBLE (-3427 3375);
FORCEADD TAP..1
(-3425 3275);
FORCEPROP 3 LASTPIN (-3475 3275) SIG_NAME M_E_CPU1_SB_DQ<16>
J 0
(-3465 3285);
DISPLAY 0.659574 (-3465 3285);
PAINT MONO (-3465 3285);
DISPLAY INVISIBLE (-3465 3285);
FORCEPROP 1 LASTPIN (-3475 3275) BN 16
J 0
(-3487 3283);
DISPLAY 0.489362 (-3487 3283);
PAINT GREEN (-3487 3283);
FORCEPROP 2 LAST CDS_LIB mstr_standard
J 0
(-3425 3275);
DISPLAY 0.723404 (-3425 3275);
PAINT MONO (-3425 3275);
DISPLAY INVISIBLE (-3425 3275);
FORCEPROP 1 LAST BODY_TYPE PLUMBING
J 0
(-3425 3325);
DISPLAY 0.872340 (-3425 3325);
PAINT GREEN (-3425 3325);
DISPLAY INVISIBLE (-3425 3325);
FORCEPROP 1 LAST HDL_TAP TRUE
J 0
(-3100 3150);
DISPLAY 0.872340 (-3100 3150);
DISPLAY INVISIBLE (-3100 3150);
FORCEPROP 1 LAST PATH I211
J 0
(-3427 3275);
DISPLAY 0.872340 (-3427 3275);
PAINT GREEN (-3427 3275);
DISPLAY INVISIBLE (-3427 3275);
FORCEADD TAP..1
(-3425 3225);
FORCEPROP 3 LASTPIN (-3475 3225) SIG_NAME M_E_CPU1_SB_DQ<17>
J 0
(-3465 3235);
DISPLAY 0.659574 (-3465 3235);
PAINT MONO (-3465 3235);
DISPLAY INVISIBLE (-3465 3235);
FORCEPROP 1 LASTPIN (-3475 3225) BN 17
J 0
(-3487 3233);
DISPLAY 0.489362 (-3487 3233);
PAINT GREEN (-3487 3233);
FORCEPROP 2 LAST CDS_LIB mstr_standard
J 0
(-3425 3225);
DISPLAY 0.723404 (-3425 3225);
PAINT MONO (-3425 3225);
DISPLAY INVISIBLE (-3425 3225);
FORCEPROP 1 LAST BODY_TYPE PLUMBING
J 0
(-3425 3275);
DISPLAY 0.872340 (-3425 3275);
PAINT GREEN (-3425 3275);
DISPLAY INVISIBLE (-3425 3275);
FORCEPROP 1 LAST HDL_TAP TRUE
J 0
(-3100 3100);
DISPLAY 0.872340 (-3100 3100);
DISPLAY INVISIBLE (-3100 3100);
FORCEPROP 1 LAST PATH I212
J 0
(-3427 3225);
DISPLAY 0.872340 (-3427 3225);
PAINT GREEN (-3427 3225);
DISPLAY INVISIBLE (-3427 3225);
FORCEADD TAP..1
(-3425 3175);
FORCEPROP 3 LASTPIN (-3475 3175) SIG_NAME M_E_CPU1_SB_DQ<18>
J 0
(-3465 3185);
DISPLAY 0.659574 (-3465 3185);
PAINT MONO (-3465 3185);
DISPLAY INVISIBLE (-3465 3185);
FORCEPROP 1 LASTPIN (-3475 3175) BN 18
J 0
(-3487 3183);
DISPLAY 0.489362 (-3487 3183);
PAINT GREEN (-3487 3183);
FORCEPROP 2 LAST CDS_LIB mstr_standard
J 0
(-3425 3175);
DISPLAY 0.723404 (-3425 3175);
PAINT MONO (-3425 3175);
DISPLAY INVISIBLE (-3425 3175);
FORCEPROP 1 LAST BODY_TYPE PLUMBING
J 0
(-3425 3225);
DISPLAY 0.872340 (-3425 3225);
PAINT GREEN (-3425 3225);
DISPLAY INVISIBLE (-3425 3225);
FORCEPROP 1 LAST HDL_TAP TRUE
J 0
(-3100 3050);
DISPLAY 0.872340 (-3100 3050);
DISPLAY INVISIBLE (-3100 3050);
FORCEPROP 1 LAST PATH I213
J 0
(-3427 3175);
DISPLAY 0.872340 (-3427 3175);
PAINT GREEN (-3427 3175);
DISPLAY INVISIBLE (-3427 3175);
FORCEADD TAP..1
(-3425 3075);
FORCEPROP 3 LASTPIN (-3475 3075) SIG_NAME M_E_CPU1_SB_DQ<20>
J 0
(-3465 3085);
DISPLAY 0.659574 (-3465 3085);
PAINT MONO (-3465 3085);
DISPLAY INVISIBLE (-3465 3085);
FORCEPROP 1 LASTPIN (-3475 3075) BN 20
J 0
(-3487 3083);
DISPLAY 0.489362 (-3487 3083);
PAINT GREEN (-3487 3083);
FORCEPROP 2 LAST CDS_LIB mstr_standard
J 0
(-3425 3075);
DISPLAY 0.723404 (-3425 3075);
PAINT MONO (-3425 3075);
DISPLAY INVISIBLE (-3425 3075);
FORCEPROP 1 LAST BODY_TYPE PLUMBING
J 0
(-3425 3125);
DISPLAY 0.872340 (-3425 3125);
PAINT GREEN (-3425 3125);
DISPLAY INVISIBLE (-3425 3125);
FORCEPROP 1 LAST HDL_TAP TRUE
J 0
(-3100 2950);
DISPLAY 0.872340 (-3100 2950);
DISPLAY INVISIBLE (-3100 2950);
FORCEPROP 1 LAST PATH I214
J 0
(-3427 3075);
DISPLAY 0.872340 (-3427 3075);
PAINT GREEN (-3427 3075);
DISPLAY INVISIBLE (-3427 3075);
FORCEADD TAP..1
(-3425 3125);
FORCEPROP 3 LASTPIN (-3475 3125) SIG_NAME M_E_CPU1_SB_DQ<19>
J 0
(-3465 3135);
DISPLAY 0.659574 (-3465 3135);
PAINT MONO (-3465 3135);
DISPLAY INVISIBLE (-3465 3135);
FORCEPROP 1 LASTPIN (-3475 3125) BN 19
J 0
(-3487 3133);
DISPLAY 0.489362 (-3487 3133);
PAINT GREEN (-3487 3133);
FORCEPROP 2 LAST CDS_LIB mstr_standard
J 0
(-3425 3125);
DISPLAY 0.723404 (-3425 3125);
PAINT MONO (-3425 3125);
DISPLAY INVISIBLE (-3425 3125);
FORCEPROP 1 LAST BODY_TYPE PLUMBING
J 0
(-3425 3175);
DISPLAY 0.872340 (-3425 3175);
PAINT GREEN (-3425 3175);
DISPLAY INVISIBLE (-3425 3175);
FORCEPROP 1 LAST HDL_TAP TRUE
J 0
(-3100 3000);
DISPLAY 0.872340 (-3100 3000);
DISPLAY INVISIBLE (-3100 3000);
FORCEPROP 1 LAST PATH I215
J 0
(-3427 3125);
DISPLAY 0.872340 (-3427 3125);
PAINT GREEN (-3427 3125);
DISPLAY INVISIBLE (-3427 3125);
FORCEADD TAP..1
(-3425 2975);
FORCEPROP 3 LASTPIN (-3475 2975) SIG_NAME M_E_CPU1_SB_DQ<22>
J 0
(-3465 2985);
DISPLAY 0.659574 (-3465 2985);
PAINT MONO (-3465 2985);
DISPLAY INVISIBLE (-3465 2985);
FORCEPROP 1 LASTPIN (-3475 2975) BN 22
J 0
(-3487 2983);
DISPLAY 0.489362 (-3487 2983);
PAINT GREEN (-3487 2983);
FORCEPROP 2 LAST CDS_LIB mstr_standard
J 0
(-3425 2975);
DISPLAY 0.723404 (-3425 2975);
PAINT MONO (-3425 2975);
DISPLAY INVISIBLE (-3425 2975);
FORCEPROP 1 LAST BODY_TYPE PLUMBING
J 0
(-3425 3025);
DISPLAY 0.872340 (-3425 3025);
PAINT GREEN (-3425 3025);
DISPLAY INVISIBLE (-3425 3025);
FORCEPROP 1 LAST HDL_TAP TRUE
J 0
(-3100 2850);
DISPLAY 0.872340 (-3100 2850);
DISPLAY INVISIBLE (-3100 2850);
FORCEPROP 1 LAST PATH I216
J 0
(-3427 2975);
DISPLAY 0.872340 (-3427 2975);
PAINT GREEN (-3427 2975);
DISPLAY INVISIBLE (-3427 2975);
FORCEADD TAP..1
(-3425 3025);
FORCEPROP 3 LASTPIN (-3475 3025) SIG_NAME M_E_CPU1_SB_DQ<21>
J 0
(-3465 3035);
DISPLAY 0.659574 (-3465 3035);
PAINT MONO (-3465 3035);
DISPLAY INVISIBLE (-3465 3035);
FORCEPROP 1 LASTPIN (-3475 3025) BN 21
J 0
(-3487 3033);
DISPLAY 0.489362 (-3487 3033);
PAINT GREEN (-3487 3033);
FORCEPROP 2 LAST CDS_LIB mstr_standard
J 0
(-3425 3025);
DISPLAY 0.723404 (-3425 3025);
PAINT MONO (-3425 3025);
DISPLAY INVISIBLE (-3425 3025);
FORCEPROP 1 LAST BODY_TYPE PLUMBING
J 0
(-3425 3075);
DISPLAY 0.872340 (-3425 3075);
PAINT GREEN (-3425 3075);
DISPLAY INVISIBLE (-3425 3075);
FORCEPROP 1 LAST HDL_TAP TRUE
J 0
(-3100 2900);
DISPLAY 0.872340 (-3100 2900);
DISPLAY INVISIBLE (-3100 2900);
FORCEPROP 1 LAST PATH I217
J 0
(-3427 3025);
DISPLAY 0.872340 (-3427 3025);
PAINT GREEN (-3427 3025);
DISPLAY INVISIBLE (-3427 3025);
FORCEADD TAP..1
(-3425 2825);
FORCEPROP 3 LASTPIN (-3475 2825) SIG_NAME M_E_CPU1_SB_DQ<24>
J 0
(-3465 2835);
DISPLAY 0.659574 (-3465 2835);
PAINT MONO (-3465 2835);
DISPLAY INVISIBLE (-3465 2835);
FORCEPROP 1 LASTPIN (-3475 2825) BN 24
J 0
(-3487 2833);
DISPLAY 0.489362 (-3487 2833);
PAINT GREEN (-3487 2833);
FORCEPROP 2 LAST CDS_LIB mstr_standard
J 0
(-3425 2825);
DISPLAY 0.723404 (-3425 2825);
PAINT MONO (-3425 2825);
DISPLAY INVISIBLE (-3425 2825);
FORCEPROP 1 LAST BODY_TYPE PLUMBING
J 0
(-3425 2875);
DISPLAY 0.872340 (-3425 2875);
PAINT GREEN (-3425 2875);
DISPLAY INVISIBLE (-3425 2875);
FORCEPROP 1 LAST HDL_TAP TRUE
J 0
(-3100 2700);
DISPLAY 0.872340 (-3100 2700);
DISPLAY INVISIBLE (-3100 2700);
FORCEPROP 1 LAST PATH I218
J 0
(-3427 2825);
DISPLAY 0.872340 (-3427 2825);
PAINT GREEN (-3427 2825);
DISPLAY INVISIBLE (-3427 2825);
FORCEADD TAP..1
(-3425 2925);
FORCEPROP 3 LASTPIN (-3475 2925) SIG_NAME M_E_CPU1_SB_DQ<23>
J 0
(-3465 2935);
DISPLAY 0.659574 (-3465 2935);
PAINT MONO (-3465 2935);
DISPLAY INVISIBLE (-3465 2935);
FORCEPROP 1 LASTPIN (-3475 2925) BN 23
J 0
(-3487 2933);
DISPLAY 0.489362 (-3487 2933);
PAINT GREEN (-3487 2933);
FORCEPROP 2 LAST CDS_LIB mstr_standard
J 0
(-3425 2925);
DISPLAY 0.723404 (-3425 2925);
PAINT MONO (-3425 2925);
DISPLAY INVISIBLE (-3425 2925);
FORCEPROP 1 LAST BODY_TYPE PLUMBING
J 0
(-3425 2975);
DISPLAY 0.872340 (-3425 2975);
PAINT GREEN (-3425 2975);
DISPLAY INVISIBLE (-3425 2975);
FORCEPROP 1 LAST HDL_TAP TRUE
J 0
(-3100 2800);
DISPLAY 0.872340 (-3100 2800);
DISPLAY INVISIBLE (-3100 2800);
FORCEPROP 1 LAST PATH I219
J 0
(-3427 2925);
DISPLAY 0.872340 (-3427 2925);
PAINT GREEN (-3427 2925);
DISPLAY INVISIBLE (-3427 2925);
FORCEADD TAP..1
(-3425 2775);
FORCEPROP 3 LASTPIN (-3475 2775) SIG_NAME M_E_CPU1_SB_DQ<25>
J 0
(-3465 2785);
DISPLAY 0.659574 (-3465 2785);
PAINT MONO (-3465 2785);
DISPLAY INVISIBLE (-3465 2785);
FORCEPROP 1 LASTPIN (-3475 2775) BN 25
J 0
(-3487 2783);
DISPLAY 0.489362 (-3487 2783);
PAINT GREEN (-3487 2783);
FORCEPROP 2 LAST CDS_LIB mstr_standard
J 0
(-3425 2775);
DISPLAY 0.723404 (-3425 2775);
PAINT MONO (-3425 2775);
DISPLAY INVISIBLE (-3425 2775);
FORCEPROP 1 LAST BODY_TYPE PLUMBING
J 0
(-3425 2825);
DISPLAY 0.872340 (-3425 2825);
PAINT GREEN (-3425 2825);
DISPLAY INVISIBLE (-3425 2825);
FORCEPROP 1 LAST HDL_TAP TRUE
J 0
(-3100 2650);
DISPLAY 0.872340 (-3100 2650);
DISPLAY INVISIBLE (-3100 2650);
FORCEPROP 1 LAST PATH I220
J 0
(-3427 2775);
DISPLAY 0.872340 (-3427 2775);
PAINT GREEN (-3427 2775);
DISPLAY INVISIBLE (-3427 2775);
FORCEADD TAP..1
(-3425 2725);
FORCEPROP 3 LASTPIN (-3475 2725) SIG_NAME M_E_CPU1_SB_DQ<26>
J 0
(-3465 2735);
DISPLAY 0.659574 (-3465 2735);
PAINT MONO (-3465 2735);
DISPLAY INVISIBLE (-3465 2735);
FORCEPROP 1 LASTPIN (-3475 2725) BN 26
J 0
(-3487 2733);
DISPLAY 0.489362 (-3487 2733);
PAINT GREEN (-3487 2733);
FORCEPROP 2 LAST CDS_LIB mstr_standard
J 0
(-3425 2725);
DISPLAY 0.723404 (-3425 2725);
PAINT MONO (-3425 2725);
DISPLAY INVISIBLE (-3425 2725);
FORCEPROP 1 LAST BODY_TYPE PLUMBING
J 0
(-3425 2775);
DISPLAY 0.872340 (-3425 2775);
PAINT GREEN (-3425 2775);
DISPLAY INVISIBLE (-3425 2775);
FORCEPROP 1 LAST HDL_TAP TRUE
J 0
(-3100 2600);
DISPLAY 0.872340 (-3100 2600);
DISPLAY INVISIBLE (-3100 2600);
FORCEPROP 1 LAST PATH I221
J 0
(-3427 2725);
DISPLAY 0.872340 (-3427 2725);
PAINT GREEN (-3427 2725);
DISPLAY INVISIBLE (-3427 2725);
FORCEADD TAP..1
(-3425 2625);
FORCEPROP 3 LASTPIN (-3475 2625) SIG_NAME M_E_CPU1_SB_DQ<28>
J 0
(-3465 2635);
DISPLAY 0.659574 (-3465 2635);
PAINT MONO (-3465 2635);
DISPLAY INVISIBLE (-3465 2635);
FORCEPROP 1 LASTPIN (-3475 2625) BN 28
J 0
(-3487 2633);
DISPLAY 0.489362 (-3487 2633);
PAINT GREEN (-3487 2633);
FORCEPROP 2 LAST CDS_LIB mstr_standard
J 0
(-3425 2625);
DISPLAY 0.723404 (-3425 2625);
PAINT MONO (-3425 2625);
DISPLAY INVISIBLE (-3425 2625);
FORCEPROP 1 LAST BODY_TYPE PLUMBING
J 0
(-3425 2675);
DISPLAY 0.872340 (-3425 2675);
PAINT GREEN (-3425 2675);
DISPLAY INVISIBLE (-3425 2675);
FORCEPROP 1 LAST HDL_TAP TRUE
J 0
(-3100 2500);
DISPLAY 0.872340 (-3100 2500);
DISPLAY INVISIBLE (-3100 2500);
FORCEPROP 1 LAST PATH I222
J 0
(-3427 2625);
DISPLAY 0.872340 (-3427 2625);
PAINT GREEN (-3427 2625);
DISPLAY INVISIBLE (-3427 2625);
FORCEADD TAP..1
(-3425 2675);
FORCEPROP 3 LASTPIN (-3475 2675) SIG_NAME M_E_CPU1_SB_DQ<27>
J 0
(-3465 2685);
DISPLAY 0.659574 (-3465 2685);
PAINT MONO (-3465 2685);
DISPLAY INVISIBLE (-3465 2685);
FORCEPROP 1 LASTPIN (-3475 2675) BN 27
J 0
(-3487 2683);
DISPLAY 0.489362 (-3487 2683);
PAINT GREEN (-3487 2683);
FORCEPROP 2 LAST CDS_LIB mstr_standard
J 0
(-3425 2675);
DISPLAY 0.723404 (-3425 2675);
PAINT MONO (-3425 2675);
DISPLAY INVISIBLE (-3425 2675);
FORCEPROP 1 LAST BODY_TYPE PLUMBING
J 0
(-3425 2725);
DISPLAY 0.872340 (-3425 2725);
PAINT GREEN (-3425 2725);
DISPLAY INVISIBLE (-3425 2725);
FORCEPROP 1 LAST HDL_TAP TRUE
J 0
(-3100 2550);
DISPLAY 0.872340 (-3100 2550);
DISPLAY INVISIBLE (-3100 2550);
FORCEPROP 1 LAST PATH I223
J 0
(-3427 2675);
DISPLAY 0.872340 (-3427 2675);
PAINT GREEN (-3427 2675);
DISPLAY INVISIBLE (-3427 2675);
FORCEADD TAP..1
(-3425 2575);
FORCEPROP 3 LASTPIN (-3475 2575) SIG_NAME M_E_CPU1_SB_DQ<29>
J 0
(-3465 2585);
DISPLAY 0.659574 (-3465 2585);
PAINT MONO (-3465 2585);
DISPLAY INVISIBLE (-3465 2585);
FORCEPROP 1 LASTPIN (-3475 2575) BN 29
J 0
(-3487 2583);
DISPLAY 0.489362 (-3487 2583);
PAINT GREEN (-3487 2583);
FORCEPROP 2 LAST CDS_LIB mstr_standard
J 0
(-3425 2575);
DISPLAY 0.723404 (-3425 2575);
PAINT MONO (-3425 2575);
DISPLAY INVISIBLE (-3425 2575);
FORCEPROP 1 LAST BODY_TYPE PLUMBING
J 0
(-3425 2625);
DISPLAY 0.872340 (-3425 2625);
PAINT GREEN (-3425 2625);
DISPLAY INVISIBLE (-3425 2625);
FORCEPROP 1 LAST HDL_TAP TRUE
J 0
(-3100 2450);
DISPLAY 0.872340 (-3100 2450);
DISPLAY INVISIBLE (-3100 2450);
FORCEPROP 1 LAST PATH I224
J 0
(-3427 2575);
DISPLAY 0.872340 (-3427 2575);
PAINT GREEN (-3427 2575);
DISPLAY INVISIBLE (-3427 2575);
FORCEADD TAP..1
(-3425 2525);
FORCEPROP 3 LASTPIN (-3475 2525) SIG_NAME M_E_CPU1_SB_DQ<30>
J 0
(-3465 2535);
DISPLAY 0.659574 (-3465 2535);
PAINT MONO (-3465 2535);
DISPLAY INVISIBLE (-3465 2535);
FORCEPROP 1 LASTPIN (-3475 2525) BN 30
J 0
(-3487 2533);
DISPLAY 0.489362 (-3487 2533);
PAINT GREEN (-3487 2533);
FORCEPROP 2 LAST CDS_LIB mstr_standard
J 0
(-3425 2525);
DISPLAY 0.723404 (-3425 2525);
PAINT MONO (-3425 2525);
DISPLAY INVISIBLE (-3425 2525);
FORCEPROP 1 LAST BODY_TYPE PLUMBING
J 0
(-3425 2575);
DISPLAY 0.872340 (-3425 2575);
PAINT GREEN (-3425 2575);
DISPLAY INVISIBLE (-3425 2575);
FORCEPROP 1 LAST HDL_TAP TRUE
J 0
(-3100 2400);
DISPLAY 0.872340 (-3100 2400);
DISPLAY INVISIBLE (-3100 2400);
FORCEPROP 1 LAST PATH I225
J 0
(-3427 2525);
DISPLAY 0.872340 (-3427 2525);
PAINT GREEN (-3427 2525);
DISPLAY INVISIBLE (-3427 2525);
FORCEADD TAP..1
(-3425 2475);
FORCEPROP 3 LASTPIN (-3475 2475) SIG_NAME M_E_CPU1_SB_DQ<31>
J 0
(-3465 2485);
DISPLAY 0.659574 (-3465 2485);
PAINT MONO (-3465 2485);
DISPLAY INVISIBLE (-3465 2485);
FORCEPROP 1 LASTPIN (-3475 2475) BN 31
J 0
(-3487 2483);
DISPLAY 0.489362 (-3487 2483);
PAINT GREEN (-3487 2483);
FORCEPROP 2 LAST CDS_LIB mstr_standard
J 0
(-3425 2475);
DISPLAY 0.723404 (-3425 2475);
PAINT MONO (-3425 2475);
DISPLAY INVISIBLE (-3425 2475);
FORCEPROP 1 LAST BODY_TYPE PLUMBING
J 0
(-3425 2525);
DISPLAY 0.872340 (-3425 2525);
PAINT GREEN (-3425 2525);
DISPLAY INVISIBLE (-3425 2525);
FORCEPROP 1 LAST HDL_TAP TRUE
J 0
(-3100 2350);
DISPLAY 0.872340 (-3100 2350);
DISPLAY INVISIBLE (-3100 2350);
FORCEPROP 1 LAST PATH I226
J 0
(-3427 2475);
DISPLAY 0.872340 (-3427 2475);
PAINT GREEN (-3427 2475);
DISPLAY INVISIBLE (-3427 2475);
FORCEADD TAP..1
(-3425 2375);
FORCEPROP 3 LASTPIN (-3475 2375) SIG_NAME M_E_CPU1_SA_CB<0>
J 0
(-3465 2385);
DISPLAY 0.659574 (-3465 2385);
PAINT MONO (-3465 2385);
DISPLAY INVISIBLE (-3465 2385);
FORCEPROP 1 LASTPIN (-3475 2375) BN 0
J 0
(-3487 2383);
DISPLAY 0.489362 (-3487 2383);
PAINT GREEN (-3487 2383);
FORCEPROP 2 LAST CDS_LIB mstr_standard
J 2
(-3425 2375);
DISPLAY 0.723404 (-3425 2375);
PAINT MONO (-3425 2375);
DISPLAY INVISIBLE (-3425 2375);
FORCEPROP 1 LAST BODY_TYPE PLUMBING
J 0
(-3425 2425);
DISPLAY 0.872340 (-3425 2425);
PAINT GREEN (-3425 2425);
DISPLAY INVISIBLE (-3425 2425);
FORCEPROP 1 LAST HDL_TAP TRUE
J 0
(-3100 2250);
DISPLAY 0.872340 (-3100 2250);
DISPLAY INVISIBLE (-3100 2250);
FORCEPROP 1 LAST PATH I227
J 0
(-3427 2375);
DISPLAY 0.872340 (-3427 2375);
PAINT GREEN (-3427 2375);
DISPLAY INVISIBLE (-3427 2375);
FORCEADD TAP..1
(-3425 2325);
FORCEPROP 3 LASTPIN (-3475 2325) SIG_NAME M_E_CPU1_SA_CB<1>
J 0
(-3465 2335);
DISPLAY 0.659574 (-3465 2335);
PAINT MONO (-3465 2335);
DISPLAY INVISIBLE (-3465 2335);
FORCEPROP 1 LASTPIN (-3475 2325) BN 1
J 0
(-3487 2333);
DISPLAY 0.489362 (-3487 2333);
PAINT GREEN (-3487 2333);
FORCEPROP 2 LAST CDS_LIB mstr_standard
J 2
(-3425 2325);
DISPLAY 0.723404 (-3425 2325);
PAINT MONO (-3425 2325);
DISPLAY INVISIBLE (-3425 2325);
FORCEPROP 1 LAST BODY_TYPE PLUMBING
J 0
(-3425 2375);
DISPLAY 0.872340 (-3425 2375);
PAINT GREEN (-3425 2375);
DISPLAY INVISIBLE (-3425 2375);
FORCEPROP 1 LAST HDL_TAP TRUE
J 0
(-3100 2200);
DISPLAY 0.872340 (-3100 2200);
DISPLAY INVISIBLE (-3100 2200);
FORCEPROP 1 LAST PATH I228
J 0
(-3427 2325);
DISPLAY 0.872340 (-3427 2325);
PAINT GREEN (-3427 2325);
DISPLAY INVISIBLE (-3427 2325);
FORCEADD TAP..1
(-3425 2225);
FORCEPROP 3 LASTPIN (-3475 2225) SIG_NAME M_E_CPU1_SA_CB<3>
J 0
(-3465 2235);
DISPLAY 0.659574 (-3465 2235);
PAINT MONO (-3465 2235);
DISPLAY INVISIBLE (-3465 2235);
FORCEPROP 1 LASTPIN (-3475 2225) BN 3
J 0
(-3487 2233);
DISPLAY 0.489362 (-3487 2233);
PAINT GREEN (-3487 2233);
FORCEPROP 2 LAST CDS_LIB mstr_standard
J 2
(-3425 2225);
DISPLAY 0.723404 (-3425 2225);
PAINT MONO (-3425 2225);
DISPLAY INVISIBLE (-3425 2225);
FORCEPROP 1 LAST BODY_TYPE PLUMBING
J 0
(-3425 2275);
DISPLAY 0.872340 (-3425 2275);
PAINT GREEN (-3425 2275);
DISPLAY INVISIBLE (-3425 2275);
FORCEPROP 1 LAST HDL_TAP TRUE
J 0
(-3100 2100);
DISPLAY 0.872340 (-3100 2100);
DISPLAY INVISIBLE (-3100 2100);
FORCEPROP 1 LAST PATH I229
J 0
(-3427 2225);
DISPLAY 0.872340 (-3427 2225);
PAINT GREEN (-3427 2225);
DISPLAY INVISIBLE (-3427 2225);
FORCEADD TAP..1
(-3425 2275);
FORCEPROP 3 LASTPIN (-3475 2275) SIG_NAME M_E_CPU1_SA_CB<2>
J 0
(-3465 2285);
DISPLAY 0.659574 (-3465 2285);
PAINT MONO (-3465 2285);
DISPLAY INVISIBLE (-3465 2285);
FORCEPROP 1 LASTPIN (-3475 2275) BN 2
J 0
(-3487 2283);
DISPLAY 0.489362 (-3487 2283);
PAINT GREEN (-3487 2283);
FORCEPROP 2 LAST CDS_LIB mstr_standard
J 2
(-3425 2275);
DISPLAY 0.723404 (-3425 2275);
PAINT MONO (-3425 2275);
DISPLAY INVISIBLE (-3425 2275);
FORCEPROP 1 LAST BODY_TYPE PLUMBING
J 0
(-3425 2325);
DISPLAY 0.872340 (-3425 2325);
PAINT GREEN (-3425 2325);
DISPLAY INVISIBLE (-3425 2325);
FORCEPROP 1 LAST HDL_TAP TRUE
J 0
(-3100 2150);
DISPLAY 0.872340 (-3100 2150);
DISPLAY INVISIBLE (-3100 2150);
FORCEPROP 1 LAST PATH I230
J 0
(-3427 2275);
DISPLAY 0.872340 (-3427 2275);
PAINT GREEN (-3427 2275);
DISPLAY INVISIBLE (-3427 2275);
FORCEADD TAP..1
(-3425 2125);
FORCEPROP 3 LASTPIN (-3475 2125) SIG_NAME M_E_CPU1_SA_CB<5>
J 0
(-3465 2135);
DISPLAY 0.659574 (-3465 2135);
PAINT MONO (-3465 2135);
DISPLAY INVISIBLE (-3465 2135);
FORCEPROP 1 LASTPIN (-3475 2125) BN 5
J 0
(-3487 2133);
DISPLAY 0.489362 (-3487 2133);
PAINT GREEN (-3487 2133);
FORCEPROP 2 LAST CDS_LIB mstr_standard
J 2
(-3425 2125);
DISPLAY 0.723404 (-3425 2125);
PAINT MONO (-3425 2125);
DISPLAY INVISIBLE (-3425 2125);
FORCEPROP 1 LAST BODY_TYPE PLUMBING
J 0
(-3425 2175);
DISPLAY 0.872340 (-3425 2175);
PAINT GREEN (-3425 2175);
DISPLAY INVISIBLE (-3425 2175);
FORCEPROP 1 LAST HDL_TAP TRUE
J 0
(-3100 2000);
DISPLAY 0.872340 (-3100 2000);
DISPLAY INVISIBLE (-3100 2000);
FORCEPROP 1 LAST PATH I231
J 0
(-3427 2125);
DISPLAY 0.872340 (-3427 2125);
PAINT GREEN (-3427 2125);
DISPLAY INVISIBLE (-3427 2125);
FORCEADD TAP..1
(-3425 2175);
FORCEPROP 3 LASTPIN (-3475 2175) SIG_NAME M_E_CPU1_SA_CB<4>
J 0
(-3465 2185);
DISPLAY 0.659574 (-3465 2185);
PAINT MONO (-3465 2185);
DISPLAY INVISIBLE (-3465 2185);
FORCEPROP 1 LASTPIN (-3475 2175) BN 4
J 0
(-3487 2183);
DISPLAY 0.489362 (-3487 2183);
PAINT GREEN (-3487 2183);
FORCEPROP 2 LAST CDS_LIB mstr_standard
J 2
(-3425 2175);
DISPLAY 0.723404 (-3425 2175);
PAINT MONO (-3425 2175);
DISPLAY INVISIBLE (-3425 2175);
FORCEPROP 1 LAST BODY_TYPE PLUMBING
J 0
(-3425 2225);
DISPLAY 0.872340 (-3425 2225);
PAINT GREEN (-3425 2225);
DISPLAY INVISIBLE (-3425 2225);
FORCEPROP 1 LAST HDL_TAP TRUE
J 0
(-3100 2050);
DISPLAY 0.872340 (-3100 2050);
DISPLAY INVISIBLE (-3100 2050);
FORCEPROP 1 LAST PATH I232
J 0
(-3427 2175);
DISPLAY 0.872340 (-3427 2175);
PAINT GREEN (-3427 2175);
DISPLAY INVISIBLE (-3427 2175);
FORCEADD TAP..1
(-3425 2075);
FORCEPROP 3 LASTPIN (-3475 2075) SIG_NAME M_E_CPU1_SA_CB<6>
J 0
(-3465 2085);
DISPLAY 0.659574 (-3465 2085);
PAINT MONO (-3465 2085);
DISPLAY INVISIBLE (-3465 2085);
FORCEPROP 1 LASTPIN (-3475 2075) BN 6
J 0
(-3487 2083);
DISPLAY 0.489362 (-3487 2083);
PAINT GREEN (-3487 2083);
FORCEPROP 2 LAST CDS_LIB mstr_standard
J 2
(-3425 2075);
DISPLAY 0.723404 (-3425 2075);
PAINT MONO (-3425 2075);
DISPLAY INVISIBLE (-3425 2075);
FORCEPROP 1 LAST BODY_TYPE PLUMBING
J 0
(-3425 2125);
DISPLAY 0.872340 (-3425 2125);
PAINT GREEN (-3425 2125);
DISPLAY INVISIBLE (-3425 2125);
FORCEPROP 1 LAST HDL_TAP TRUE
J 0
(-3100 1950);
DISPLAY 0.872340 (-3100 1950);
DISPLAY INVISIBLE (-3100 1950);
FORCEPROP 1 LAST PATH I233
J 0
(-3427 2075);
DISPLAY 0.872340 (-3427 2075);
PAINT GREEN (-3427 2075);
DISPLAY INVISIBLE (-3427 2075);
FORCEADD OFFPAGE..6
R 2
(-2825 1975);
FORCEPROP 2 LAST $XR0 101 
J 0
(-2611 1975);
DISPLAY 0.638298 (-2611 1975);
PAINT MONO (-2611 1975);
FORCEPROP 2 LAST PATH I234
J 0
(-2600 2025);
DISPLAY 1.021277 (-2600 2025);
DISPLAY INVISIBLE (-2600 2025);
FORCEPROP 1 LAST COMMENT_BODY TRUE
J 2
(-2925 1900);
DISPLAY 0.872340 (-2925 1900);
PAINT GREEN (-2925 1900);
DISPLAY INVISIBLE (-2925 1900);
FORCEPROP 1 LAST OFFPAGE TRUE
J 2
(-3150 1850);
DISPLAY 0.872340 (-3150 1850);
PAINT GREEN (-3150 1850);
DISPLAY INVISIBLE (-3150 1850);
FORCEPROP 2 LAST CDS_LIB mstr_standard
J 2
(-2825 1975);
DISPLAY 0.723404 (-2825 1975);
PAINT MONO (-2825 1975);
DISPLAY INVISIBLE (-2825 1975);
FORCEADD TAP..1
(-3425 2025);
FORCEPROP 3 LASTPIN (-3475 2025) SIG_NAME M_E_CPU1_SA_CB<7>
J 0
(-3465 2035);
DISPLAY 0.659574 (-3465 2035);
PAINT MONO (-3465 2035);
DISPLAY INVISIBLE (-3465 2035);
FORCEPROP 1 LASTPIN (-3475 2025) BN 7
J 0
(-3487 2033);
DISPLAY 0.489362 (-3487 2033);
PAINT GREEN (-3487 2033);
FORCEPROP 2 LAST CDS_LIB mstr_standard
J 2
(-3425 2025);
DISPLAY 0.723404 (-3425 2025);
PAINT MONO (-3425 2025);
DISPLAY INVISIBLE (-3425 2025);
FORCEPROP 1 LAST BODY_TYPE PLUMBING
J 0
(-3425 2075);
DISPLAY 0.872340 (-3425 2075);
PAINT GREEN (-3425 2075);
DISPLAY INVISIBLE (-3425 2075);
FORCEPROP 1 LAST HDL_TAP TRUE
J 0
(-3100 1900);
DISPLAY 0.872340 (-3100 1900);
DISPLAY INVISIBLE (-3100 1900);
FORCEPROP 1 LAST PATH I235
J 0
(-3427 2025);
DISPLAY 0.872340 (-3427 2025);
PAINT GREEN (-3427 2025);
DISPLAY INVISIBLE (-3427 2025);
FORCEADD TAP..1
(-3425 1925);
FORCEPROP 3 LASTPIN (-3475 1925) SIG_NAME M_E_CPU1_SB_CB<0>
J 0
(-3465 1935);
DISPLAY 0.659574 (-3465 1935);
PAINT MONO (-3465 1935);
DISPLAY INVISIBLE (-3465 1935);
FORCEPROP 1 LASTPIN (-3475 1925) BN 0
J 0
(-3487 1933);
DISPLAY 0.489362 (-3487 1933);
PAINT GREEN (-3487 1933);
FORCEPROP 2 LAST CDS_LIB mstr_standard
J 2
(-3425 1925);
DISPLAY 0.723404 (-3425 1925);
PAINT MONO (-3425 1925);
DISPLAY INVISIBLE (-3425 1925);
FORCEPROP 1 LAST BODY_TYPE PLUMBING
J 0
(-3425 1975);
DISPLAY 0.872340 (-3425 1975);
PAINT GREEN (-3425 1975);
DISPLAY INVISIBLE (-3425 1975);
FORCEPROP 1 LAST HDL_TAP TRUE
J 0
(-3100 1800);
DISPLAY 0.872340 (-3100 1800);
DISPLAY INVISIBLE (-3100 1800);
FORCEPROP 1 LAST PATH I236
J 0
(-3427 1925);
DISPLAY 0.872340 (-3427 1925);
PAINT GREEN (-3427 1925);
DISPLAY INVISIBLE (-3427 1925);
FORCEADD TAP..1
(-3425 1875);
FORCEPROP 3 LASTPIN (-3475 1875) SIG_NAME M_E_CPU1_SB_CB<1>
J 0
(-3465 1885);
DISPLAY 0.659574 (-3465 1885);
PAINT MONO (-3465 1885);
DISPLAY INVISIBLE (-3465 1885);
FORCEPROP 1 LASTPIN (-3475 1875) BN 1
J 0
(-3487 1883);
DISPLAY 0.489362 (-3487 1883);
PAINT GREEN (-3487 1883);
FORCEPROP 2 LAST CDS_LIB mstr_standard
J 2
(-3425 1875);
DISPLAY 0.723404 (-3425 1875);
PAINT MONO (-3425 1875);
DISPLAY INVISIBLE (-3425 1875);
FORCEPROP 1 LAST BODY_TYPE PLUMBING
J 0
(-3425 1925);
DISPLAY 0.872340 (-3425 1925);
PAINT GREEN (-3425 1925);
DISPLAY INVISIBLE (-3425 1925);
FORCEPROP 1 LAST HDL_TAP TRUE
J 0
(-3100 1750);
DISPLAY 0.872340 (-3100 1750);
DISPLAY INVISIBLE (-3100 1750);
FORCEPROP 1 LAST PATH I237
J 0
(-3427 1875);
DISPLAY 0.872340 (-3427 1875);
PAINT GREEN (-3427 1875);
DISPLAY INVISIBLE (-3427 1875);
FORCEADD TAP..1
(-3425 1825);
FORCEPROP 3 LASTPIN (-3475 1825) SIG_NAME M_E_CPU1_SB_CB<2>
J 0
(-3465 1835);
DISPLAY 0.659574 (-3465 1835);
PAINT MONO (-3465 1835);
DISPLAY INVISIBLE (-3465 1835);
FORCEPROP 1 LASTPIN (-3475 1825) BN 2
J 0
(-3487 1833);
DISPLAY 0.489362 (-3487 1833);
PAINT GREEN (-3487 1833);
FORCEPROP 2 LAST CDS_LIB mstr_standard
J 2
(-3425 1825);
DISPLAY 0.723404 (-3425 1825);
PAINT MONO (-3425 1825);
DISPLAY INVISIBLE (-3425 1825);
FORCEPROP 1 LAST BODY_TYPE PLUMBING
J 0
(-3425 1875);
DISPLAY 0.872340 (-3425 1875);
PAINT GREEN (-3425 1875);
DISPLAY INVISIBLE (-3425 1875);
FORCEPROP 1 LAST HDL_TAP TRUE
J 0
(-3100 1700);
DISPLAY 0.872340 (-3100 1700);
DISPLAY INVISIBLE (-3100 1700);
FORCEPROP 1 LAST PATH I238
J 0
(-3427 1825);
DISPLAY 0.872340 (-3427 1825);
PAINT GREEN (-3427 1825);
DISPLAY INVISIBLE (-3427 1825);
FORCEADD TAP..1
(-3425 1775);
FORCEPROP 3 LASTPIN (-3475 1775) SIG_NAME M_E_CPU1_SB_CB<3>
J 0
(-3465 1785);
DISPLAY 0.659574 (-3465 1785);
PAINT MONO (-3465 1785);
DISPLAY INVISIBLE (-3465 1785);
FORCEPROP 1 LASTPIN (-3475 1775) BN 3
J 0
(-3487 1783);
DISPLAY 0.489362 (-3487 1783);
PAINT GREEN (-3487 1783);
FORCEPROP 2 LAST CDS_LIB mstr_standard
J 2
(-3425 1775);
DISPLAY 0.723404 (-3425 1775);
PAINT MONO (-3425 1775);
DISPLAY INVISIBLE (-3425 1775);
FORCEPROP 1 LAST BODY_TYPE PLUMBING
J 0
(-3425 1825);
DISPLAY 0.872340 (-3425 1825);
PAINT GREEN (-3425 1825);
DISPLAY INVISIBLE (-3425 1825);
FORCEPROP 1 LAST HDL_TAP TRUE
J 0
(-3100 1650);
DISPLAY 0.872340 (-3100 1650);
DISPLAY INVISIBLE (-3100 1650);
FORCEPROP 1 LAST PATH I239
J 0
(-3427 1775);
DISPLAY 0.872340 (-3427 1775);
PAINT GREEN (-3427 1775);
DISPLAY INVISIBLE (-3427 1775);
FORCEADD TAP..1
(-3425 1675);
FORCEPROP 3 LASTPIN (-3475 1675) SIG_NAME M_E_CPU1_SB_CB<5>
J 0
(-3465 1685);
DISPLAY 0.659574 (-3465 1685);
PAINT MONO (-3465 1685);
DISPLAY INVISIBLE (-3465 1685);
FORCEPROP 1 LASTPIN (-3475 1675) BN 5
J 0
(-3487 1683);
DISPLAY 0.489362 (-3487 1683);
PAINT GREEN (-3487 1683);
FORCEPROP 2 LAST CDS_LIB mstr_standard
J 2
(-3425 1675);
DISPLAY 0.723404 (-3425 1675);
PAINT MONO (-3425 1675);
DISPLAY INVISIBLE (-3425 1675);
FORCEPROP 1 LAST BODY_TYPE PLUMBING
J 0
(-3425 1725);
DISPLAY 0.872340 (-3425 1725);
PAINT GREEN (-3425 1725);
DISPLAY INVISIBLE (-3425 1725);
FORCEPROP 1 LAST HDL_TAP TRUE
J 0
(-3100 1550);
DISPLAY 0.872340 (-3100 1550);
DISPLAY INVISIBLE (-3100 1550);
FORCEPROP 1 LAST PATH I240
J 0
(-3427 1675);
DISPLAY 0.872340 (-3427 1675);
PAINT GREEN (-3427 1675);
DISPLAY INVISIBLE (-3427 1675);
FORCEADD TAP..1
(-3425 1725);
FORCEPROP 3 LASTPIN (-3475 1725) SIG_NAME M_E_CPU1_SB_CB<4>
J 0
(-3465 1735);
DISPLAY 0.659574 (-3465 1735);
PAINT MONO (-3465 1735);
DISPLAY INVISIBLE (-3465 1735);
FORCEPROP 1 LASTPIN (-3475 1725) BN 4
J 0
(-3487 1733);
DISPLAY 0.489362 (-3487 1733);
PAINT GREEN (-3487 1733);
FORCEPROP 2 LAST CDS_LIB mstr_standard
J 2
(-3425 1725);
DISPLAY 0.723404 (-3425 1725);
PAINT MONO (-3425 1725);
DISPLAY INVISIBLE (-3425 1725);
FORCEPROP 1 LAST BODY_TYPE PLUMBING
J 0
(-3425 1775);
DISPLAY 0.872340 (-3425 1775);
PAINT GREEN (-3425 1775);
DISPLAY INVISIBLE (-3425 1775);
FORCEPROP 1 LAST HDL_TAP TRUE
J 0
(-3100 1600);
DISPLAY 0.872340 (-3100 1600);
DISPLAY INVISIBLE (-3100 1600);
FORCEPROP 1 LAST PATH I241
J 0
(-3427 1725);
DISPLAY 0.872340 (-3427 1725);
PAINT GREEN (-3427 1725);
DISPLAY INVISIBLE (-3427 1725);
FORCEADD TAP..1
(-3425 1625);
FORCEPROP 3 LASTPIN (-3475 1625) SIG_NAME M_E_CPU1_SB_CB<6>
J 0
(-3465 1635);
DISPLAY 0.659574 (-3465 1635);
PAINT MONO (-3465 1635);
DISPLAY INVISIBLE (-3465 1635);
FORCEPROP 1 LASTPIN (-3475 1625) BN 6
J 0
(-3487 1633);
DISPLAY 0.489362 (-3487 1633);
PAINT GREEN (-3487 1633);
FORCEPROP 2 LAST CDS_LIB mstr_standard
J 2
(-3425 1625);
DISPLAY 0.723404 (-3425 1625);
PAINT MONO (-3425 1625);
DISPLAY INVISIBLE (-3425 1625);
FORCEPROP 1 LAST BODY_TYPE PLUMBING
J 0
(-3425 1675);
DISPLAY 0.872340 (-3425 1675);
PAINT GREEN (-3425 1675);
DISPLAY INVISIBLE (-3425 1675);
FORCEPROP 1 LAST HDL_TAP TRUE
J 0
(-3100 1500);
DISPLAY 0.872340 (-3100 1500);
DISPLAY INVISIBLE (-3100 1500);
FORCEPROP 1 LAST PATH I242
J 0
(-3427 1625);
DISPLAY 0.872340 (-3427 1625);
PAINT GREEN (-3427 1625);
DISPLAY INVISIBLE (-3427 1625);
FORCEADD TAP..1
(-3425 1575);
FORCEPROP 3 LASTPIN (-3475 1575) SIG_NAME M_E_CPU1_SB_CB<7>
J 0
(-3465 1585);
DISPLAY 0.659574 (-3465 1585);
PAINT MONO (-3465 1585);
DISPLAY INVISIBLE (-3465 1585);
FORCEPROP 1 LASTPIN (-3475 1575) BN 7
J 0
(-3487 1583);
DISPLAY 0.489362 (-3487 1583);
PAINT GREEN (-3487 1583);
FORCEPROP 2 LAST CDS_LIB mstr_standard
J 2
(-3425 1575);
DISPLAY 0.723404 (-3425 1575);
PAINT MONO (-3425 1575);
DISPLAY INVISIBLE (-3425 1575);
FORCEPROP 1 LAST BODY_TYPE PLUMBING
J 0
(-3425 1625);
DISPLAY 0.872340 (-3425 1625);
PAINT GREEN (-3425 1625);
DISPLAY INVISIBLE (-3425 1625);
FORCEPROP 1 LAST HDL_TAP TRUE
J 0
(-3100 1450);
DISPLAY 0.872340 (-3100 1450);
DISPLAY INVISIBLE (-3100 1450);
FORCEPROP 1 LAST PATH I243
J 0
(-3427 1575);
DISPLAY 0.872340 (-3427 1575);
PAINT GREEN (-3427 1575);
DISPLAY INVISIBLE (-3427 1575);
FORCEADD TAP..1
R 2
(-5850 5975);
FORCEPROP 3 LASTPIN (-5800 5975) SIG_NAME M_E_CPU1_SA_DQS_DP<0>
J 0
(-5790 5985);
DISPLAY 0.659574 (-5790 5985);
PAINT MONO (-5790 5985);
DISPLAY INVISIBLE (-5790 5985);
FORCEPROP 1 LASTPIN (-5800 5975) BN 0
J 2
(-5788 5983);
DISPLAY 0.489362 (-5788 5983);
PAINT GREEN (-5788 5983);
FORCEPROP 2 LAST CDS_LIB mstr_standard
J 2
(-5850 5975);
DISPLAY 0.723404 (-5850 5975);
PAINT MONO (-5850 5975);
DISPLAY INVISIBLE (-5850 5975);
FORCEPROP 1 LAST BODY_TYPE PLUMBING
J 2
(-5850 6025);
DISPLAY 0.872340 (-5850 6025);
PAINT GREEN (-5850 6025);
DISPLAY INVISIBLE (-5850 6025);
FORCEPROP 1 LAST HDL_TAP TRUE
J 2
(-6175 5850);
DISPLAY 0.872340 (-6175 5850);
DISPLAY INVISIBLE (-6175 5850);
FORCEPROP 1 LAST PATH I244
J 2
(-5848 5975);
DISPLAY 0.872340 (-5848 5975);
PAINT GREEN (-5848 5975);
DISPLAY INVISIBLE (-5848 5975);
FORCEADD TAP..1
R 2
(-5850 5875);
FORCEPROP 3 LASTPIN (-5800 5875) SIG_NAME M_E_CPU1_SA_DQS_DP<1>
J 0
(-5790 5885);
DISPLAY 0.659574 (-5790 5885);
PAINT MONO (-5790 5885);
DISPLAY INVISIBLE (-5790 5885);
FORCEPROP 1 LASTPIN (-5800 5875) BN 1
J 2
(-5788 5883);
DISPLAY 0.489362 (-5788 5883);
PAINT GREEN (-5788 5883);
FORCEPROP 2 LAST CDS_LIB mstr_standard
J 2
(-5850 5875);
DISPLAY 0.723404 (-5850 5875);
PAINT MONO (-5850 5875);
DISPLAY INVISIBLE (-5850 5875);
FORCEPROP 1 LAST BODY_TYPE PLUMBING
J 2
(-5850 5925);
DISPLAY 0.872340 (-5850 5925);
PAINT GREEN (-5850 5925);
DISPLAY INVISIBLE (-5850 5925);
FORCEPROP 1 LAST HDL_TAP TRUE
J 2
(-6175 5750);
DISPLAY 0.872340 (-6175 5750);
DISPLAY INVISIBLE (-6175 5750);
FORCEPROP 1 LAST PATH I245
J 2
(-5848 5875);
DISPLAY 0.872340 (-5848 5875);
PAINT GREEN (-5848 5875);
DISPLAY INVISIBLE (-5848 5875);
FORCEADD TAP..1
R 2
(-5850 5675);
FORCEPROP 3 LASTPIN (-5800 5675) SIG_NAME M_E_CPU1_SA_DQS_DP<3>
J 0
(-5790 5685);
DISPLAY 0.659574 (-5790 5685);
PAINT MONO (-5790 5685);
DISPLAY INVISIBLE (-5790 5685);
FORCEPROP 1 LASTPIN (-5800 5675) BN 3
J 2
(-5788 5683);
DISPLAY 0.489362 (-5788 5683);
PAINT GREEN (-5788 5683);
FORCEPROP 2 LAST CDS_LIB mstr_standard
J 2
(-5850 5675);
DISPLAY 0.723404 (-5850 5675);
PAINT MONO (-5850 5675);
DISPLAY INVISIBLE (-5850 5675);
FORCEPROP 1 LAST BODY_TYPE PLUMBING
J 2
(-5850 5725);
DISPLAY 0.872340 (-5850 5725);
PAINT GREEN (-5850 5725);
DISPLAY INVISIBLE (-5850 5725);
FORCEPROP 1 LAST HDL_TAP TRUE
J 2
(-6175 5550);
DISPLAY 0.872340 (-6175 5550);
DISPLAY INVISIBLE (-6175 5550);
FORCEPROP 1 LAST PATH I246
J 2
(-5848 5675);
DISPLAY 0.872340 (-5848 5675);
PAINT GREEN (-5848 5675);
DISPLAY INVISIBLE (-5848 5675);
FORCEADD TAP..1
R 2
(-5850 5775);
FORCEPROP 3 LASTPIN (-5800 5775) SIG_NAME M_E_CPU1_SA_DQS_DP<2>
J 0
(-5790 5785);
DISPLAY 0.659574 (-5790 5785);
PAINT MONO (-5790 5785);
DISPLAY INVISIBLE (-5790 5785);
FORCEPROP 1 LASTPIN (-5800 5775) BN 2
J 2
(-5788 5783);
DISPLAY 0.489362 (-5788 5783);
PAINT GREEN (-5788 5783);
FORCEPROP 2 LAST CDS_LIB mstr_standard
J 2
(-5850 5775);
DISPLAY 0.723404 (-5850 5775);
PAINT MONO (-5850 5775);
DISPLAY INVISIBLE (-5850 5775);
FORCEPROP 1 LAST BODY_TYPE PLUMBING
J 2
(-5850 5825);
DISPLAY 0.872340 (-5850 5825);
PAINT GREEN (-5850 5825);
DISPLAY INVISIBLE (-5850 5825);
FORCEPROP 1 LAST HDL_TAP TRUE
J 2
(-6175 5650);
DISPLAY 0.872340 (-6175 5650);
DISPLAY INVISIBLE (-6175 5650);
FORCEPROP 1 LAST PATH I247
J 2
(-5848 5775);
DISPLAY 0.872340 (-5848 5775);
PAINT GREEN (-5848 5775);
DISPLAY INVISIBLE (-5848 5775);
FORCEADD TAP..1
R 2
(-6050 5925);
FORCEPROP 3 LASTPIN (-6000 5925) SIG_NAME M_E_CPU1_SA_DQS_DN<0>
J 0
(-5990 5935);
DISPLAY 0.659574 (-5990 5935);
PAINT MONO (-5990 5935);
DISPLAY INVISIBLE (-5990 5935);
FORCEPROP 1 LASTPIN (-6000 5925) BN 0
J 2
(-5988 5933);
DISPLAY 0.489362 (-5988 5933);
PAINT GREEN (-5988 5933);
FORCEPROP 2 LAST CDS_LIB mstr_standard
J 2
(-6050 5925);
DISPLAY 0.723404 (-6050 5925);
PAINT MONO (-6050 5925);
DISPLAY INVISIBLE (-6050 5925);
FORCEPROP 1 LAST BODY_TYPE PLUMBING
J 2
(-6050 5975);
DISPLAY 0.872340 (-6050 5975);
PAINT GREEN (-6050 5975);
DISPLAY INVISIBLE (-6050 5975);
FORCEPROP 1 LAST HDL_TAP TRUE
J 2
(-6375 5800);
DISPLAY 0.872340 (-6375 5800);
DISPLAY INVISIBLE (-6375 5800);
FORCEPROP 1 LAST PATH I248
J 2
(-6048 5925);
DISPLAY 0.872340 (-6048 5925);
PAINT GREEN (-6048 5925);
DISPLAY INVISIBLE (-6048 5925);
FORCEADD TAP..1
R 2
(-6050 5825);
FORCEPROP 3 LASTPIN (-6000 5825) SIG_NAME M_E_CPU1_SA_DQS_DN<1>
J 0
(-5990 5835);
DISPLAY 0.659574 (-5990 5835);
PAINT MONO (-5990 5835);
DISPLAY INVISIBLE (-5990 5835);
FORCEPROP 1 LASTPIN (-6000 5825) BN 1
J 2
(-5988 5833);
DISPLAY 0.489362 (-5988 5833);
PAINT GREEN (-5988 5833);
FORCEPROP 2 LAST CDS_LIB mstr_standard
J 2
(-6050 5825);
DISPLAY 0.723404 (-6050 5825);
PAINT MONO (-6050 5825);
DISPLAY INVISIBLE (-6050 5825);
FORCEPROP 1 LAST BODY_TYPE PLUMBING
J 2
(-6050 5875);
DISPLAY 0.872340 (-6050 5875);
PAINT GREEN (-6050 5875);
DISPLAY INVISIBLE (-6050 5875);
FORCEPROP 1 LAST HDL_TAP TRUE
J 2
(-6375 5700);
DISPLAY 0.872340 (-6375 5700);
DISPLAY INVISIBLE (-6375 5700);
FORCEPROP 1 LAST PATH I249
J 2
(-6048 5825);
DISPLAY 0.872340 (-6048 5825);
PAINT GREEN (-6048 5825);
DISPLAY INVISIBLE (-6048 5825);
FORCEADD TAP..1
R 2
(-6050 5725);
FORCEPROP 3 LASTPIN (-6000 5725) SIG_NAME M_E_CPU1_SA_DQS_DN<2>
J 0
(-5990 5735);
DISPLAY 0.659574 (-5990 5735);
PAINT MONO (-5990 5735);
DISPLAY INVISIBLE (-5990 5735);
FORCEPROP 1 LASTPIN (-6000 5725) BN 2
J 2
(-5988 5733);
DISPLAY 0.489362 (-5988 5733);
PAINT GREEN (-5988 5733);
FORCEPROP 2 LAST CDS_LIB mstr_standard
J 2
(-6050 5725);
DISPLAY 0.723404 (-6050 5725);
PAINT MONO (-6050 5725);
DISPLAY INVISIBLE (-6050 5725);
FORCEPROP 1 LAST BODY_TYPE PLUMBING
J 2
(-6050 5775);
DISPLAY 0.872340 (-6050 5775);
PAINT GREEN (-6050 5775);
DISPLAY INVISIBLE (-6050 5775);
FORCEPROP 1 LAST HDL_TAP TRUE
J 2
(-6375 5600);
DISPLAY 0.872340 (-6375 5600);
DISPLAY INVISIBLE (-6375 5600);
FORCEPROP 1 LAST PATH I250
J 2
(-6048 5725);
DISPLAY 0.872340 (-6048 5725);
PAINT GREEN (-6048 5725);
DISPLAY INVISIBLE (-6048 5725);
FORCEADD TAP..1
R 2
(-5850 5475);
FORCEPROP 3 LASTPIN (-5800 5475) SIG_NAME M_E_CPU1_SA_DQS_DP<5>
J 0
(-5790 5485);
DISPLAY 0.659574 (-5790 5485);
PAINT MONO (-5790 5485);
DISPLAY INVISIBLE (-5790 5485);
FORCEPROP 1 LASTPIN (-5800 5475) BN 5
J 2
(-5788 5483);
DISPLAY 0.489362 (-5788 5483);
PAINT GREEN (-5788 5483);
FORCEPROP 2 LAST CDS_LIB mstr_standard
J 2
(-5850 5475);
DISPLAY 0.723404 (-5850 5475);
PAINT MONO (-5850 5475);
DISPLAY INVISIBLE (-5850 5475);
FORCEPROP 1 LAST BODY_TYPE PLUMBING
J 2
(-5850 5525);
DISPLAY 0.872340 (-5850 5525);
PAINT GREEN (-5850 5525);
DISPLAY INVISIBLE (-5850 5525);
FORCEPROP 1 LAST HDL_TAP TRUE
J 2
(-6175 5350);
DISPLAY 0.872340 (-6175 5350);
DISPLAY INVISIBLE (-6175 5350);
FORCEPROP 1 LAST PATH I251
J 2
(-5848 5475);
DISPLAY 0.872340 (-5848 5475);
PAINT GREEN (-5848 5475);
DISPLAY INVISIBLE (-5848 5475);
FORCEADD TAP..1
R 2
(-5850 5575);
FORCEPROP 3 LASTPIN (-5800 5575) SIG_NAME M_E_CPU1_SA_DQS_DP<4>
J 0
(-5790 5585);
DISPLAY 0.659574 (-5790 5585);
PAINT MONO (-5790 5585);
DISPLAY INVISIBLE (-5790 5585);
FORCEPROP 1 LASTPIN (-5800 5575) BN 4
J 2
(-5788 5583);
DISPLAY 0.489362 (-5788 5583);
PAINT GREEN (-5788 5583);
FORCEPROP 2 LAST CDS_LIB mstr_standard
J 2
(-5850 5575);
DISPLAY 0.723404 (-5850 5575);
PAINT MONO (-5850 5575);
DISPLAY INVISIBLE (-5850 5575);
FORCEPROP 1 LAST BODY_TYPE PLUMBING
J 2
(-5850 5625);
DISPLAY 0.872340 (-5850 5625);
PAINT GREEN (-5850 5625);
DISPLAY INVISIBLE (-5850 5625);
FORCEPROP 1 LAST HDL_TAP TRUE
J 2
(-6175 5450);
DISPLAY 0.872340 (-6175 5450);
DISPLAY INVISIBLE (-6175 5450);
FORCEPROP 1 LAST PATH I252
J 2
(-5848 5575);
DISPLAY 0.872340 (-5848 5575);
PAINT GREEN (-5848 5575);
DISPLAY INVISIBLE (-5848 5575);
FORCEADD TAP..1
R 2
(-5850 5375);
FORCEPROP 3 LASTPIN (-5800 5375) SIG_NAME M_E_CPU1_SA_DQS_DP<6>
J 0
(-5790 5385);
DISPLAY 0.659574 (-5790 5385);
PAINT MONO (-5790 5385);
DISPLAY INVISIBLE (-5790 5385);
FORCEPROP 1 LASTPIN (-5800 5375) BN 6
J 2
(-5788 5383);
DISPLAY 0.489362 (-5788 5383);
PAINT GREEN (-5788 5383);
FORCEPROP 2 LAST CDS_LIB mstr_standard
J 2
(-5850 5375);
DISPLAY 0.723404 (-5850 5375);
PAINT MONO (-5850 5375);
DISPLAY INVISIBLE (-5850 5375);
FORCEPROP 1 LAST BODY_TYPE PLUMBING
J 2
(-5850 5425);
DISPLAY 0.872340 (-5850 5425);
PAINT GREEN (-5850 5425);
DISPLAY INVISIBLE (-5850 5425);
FORCEPROP 1 LAST HDL_TAP TRUE
J 2
(-6175 5250);
DISPLAY 0.872340 (-6175 5250);
DISPLAY INVISIBLE (-6175 5250);
FORCEPROP 1 LAST PATH I253
J 2
(-5848 5375);
DISPLAY 0.872340 (-5848 5375);
PAINT GREEN (-5848 5375);
DISPLAY INVISIBLE (-5848 5375);
FORCEADD TAP..1
R 2
(-5850 5175);
FORCEPROP 3 LASTPIN (-5800 5175) SIG_NAME M_E_CPU1_SA_DQS_DP<8>
J 0
(-5790 5185);
DISPLAY 0.659574 (-5790 5185);
PAINT MONO (-5790 5185);
DISPLAY INVISIBLE (-5790 5185);
FORCEPROP 1 LASTPIN (-5800 5175) BN 8
J 2
(-5788 5183);
DISPLAY 0.489362 (-5788 5183);
PAINT GREEN (-5788 5183);
FORCEPROP 2 LAST CDS_LIB mstr_standard
J 2
(-5850 5175);
DISPLAY 0.723404 (-5850 5175);
PAINT MONO (-5850 5175);
DISPLAY INVISIBLE (-5850 5175);
FORCEPROP 1 LAST BODY_TYPE PLUMBING
J 2
(-5850 5225);
DISPLAY 0.872340 (-5850 5225);
PAINT GREEN (-5850 5225);
DISPLAY INVISIBLE (-5850 5225);
FORCEPROP 1 LAST HDL_TAP TRUE
J 2
(-6175 5050);
DISPLAY 0.872340 (-6175 5050);
DISPLAY INVISIBLE (-6175 5050);
FORCEPROP 1 LAST PATH I254
J 2
(-5848 5175);
DISPLAY 0.872340 (-5848 5175);
PAINT GREEN (-5848 5175);
DISPLAY INVISIBLE (-5848 5175);
FORCEADD TAP..1
R 2
(-5850 5275);
FORCEPROP 3 LASTPIN (-5800 5275) SIG_NAME M_E_CPU1_SA_DQS_DP<7>
J 0
(-5790 5285);
DISPLAY 0.659574 (-5790 5285);
PAINT MONO (-5790 5285);
DISPLAY INVISIBLE (-5790 5285);
FORCEPROP 1 LASTPIN (-5800 5275) BN 7
J 2
(-5788 5283);
DISPLAY 0.489362 (-5788 5283);
PAINT GREEN (-5788 5283);
FORCEPROP 2 LAST CDS_LIB mstr_standard
J 2
(-5850 5275);
DISPLAY 0.723404 (-5850 5275);
PAINT MONO (-5850 5275);
DISPLAY INVISIBLE (-5850 5275);
FORCEPROP 1 LAST BODY_TYPE PLUMBING
J 2
(-5850 5325);
DISPLAY 0.872340 (-5850 5325);
PAINT GREEN (-5850 5325);
DISPLAY INVISIBLE (-5850 5325);
FORCEPROP 1 LAST HDL_TAP TRUE
J 2
(-6175 5150);
DISPLAY 0.872340 (-6175 5150);
DISPLAY INVISIBLE (-6175 5150);
FORCEPROP 1 LAST PATH I255
J 2
(-5848 5275);
DISPLAY 0.872340 (-5848 5275);
PAINT GREEN (-5848 5275);
DISPLAY INVISIBLE (-5848 5275);
FORCEADD TAP..1
R 2
(-6050 5625);
FORCEPROP 3 LASTPIN (-6000 5625) SIG_NAME M_E_CPU1_SA_DQS_DN<3>
J 0
(-5990 5635);
DISPLAY 0.659574 (-5990 5635);
PAINT MONO (-5990 5635);
DISPLAY INVISIBLE (-5990 5635);
FORCEPROP 1 LASTPIN (-6000 5625) BN 3
J 2
(-5988 5633);
DISPLAY 0.489362 (-5988 5633);
PAINT GREEN (-5988 5633);
FORCEPROP 2 LAST CDS_LIB mstr_standard
J 2
(-6050 5625);
DISPLAY 0.723404 (-6050 5625);
PAINT MONO (-6050 5625);
DISPLAY INVISIBLE (-6050 5625);
FORCEPROP 1 LAST BODY_TYPE PLUMBING
J 2
(-6050 5675);
DISPLAY 0.872340 (-6050 5675);
PAINT GREEN (-6050 5675);
DISPLAY INVISIBLE (-6050 5675);
FORCEPROP 1 LAST HDL_TAP TRUE
J 2
(-6375 5500);
DISPLAY 0.872340 (-6375 5500);
DISPLAY INVISIBLE (-6375 5500);
FORCEPROP 1 LAST PATH I256
J 2
(-6048 5625);
DISPLAY 0.872340 (-6048 5625);
PAINT GREEN (-6048 5625);
DISPLAY INVISIBLE (-6048 5625);
FORCEADD TAP..1
R 2
(-6050 5525);
FORCEPROP 3 LASTPIN (-6000 5525) SIG_NAME M_E_CPU1_SA_DQS_DN<4>
J 0
(-5990 5535);
DISPLAY 0.659574 (-5990 5535);
PAINT MONO (-5990 5535);
DISPLAY INVISIBLE (-5990 5535);
FORCEPROP 1 LASTPIN (-6000 5525) BN 4
J 2
(-5988 5533);
DISPLAY 0.489362 (-5988 5533);
PAINT GREEN (-5988 5533);
FORCEPROP 2 LAST CDS_LIB mstr_standard
J 2
(-6050 5525);
DISPLAY 0.723404 (-6050 5525);
PAINT MONO (-6050 5525);
DISPLAY INVISIBLE (-6050 5525);
FORCEPROP 1 LAST BODY_TYPE PLUMBING
J 2
(-6050 5575);
DISPLAY 0.872340 (-6050 5575);
PAINT GREEN (-6050 5575);
DISPLAY INVISIBLE (-6050 5575);
FORCEPROP 1 LAST HDL_TAP TRUE
J 2
(-6375 5400);
DISPLAY 0.872340 (-6375 5400);
DISPLAY INVISIBLE (-6375 5400);
FORCEPROP 1 LAST PATH I257
J 2
(-6048 5525);
DISPLAY 0.872340 (-6048 5525);
PAINT GREEN (-6048 5525);
DISPLAY INVISIBLE (-6048 5525);
FORCEADD TAP..1
R 2
(-6050 5425);
FORCEPROP 3 LASTPIN (-6000 5425) SIG_NAME M_E_CPU1_SA_DQS_DN<5>
J 0
(-5990 5435);
DISPLAY 0.659574 (-5990 5435);
PAINT MONO (-5990 5435);
DISPLAY INVISIBLE (-5990 5435);
FORCEPROP 1 LASTPIN (-6000 5425) BN 5
J 2
(-5988 5433);
DISPLAY 0.489362 (-5988 5433);
PAINT GREEN (-5988 5433);
FORCEPROP 2 LAST CDS_LIB mstr_standard
J 2
(-6050 5425);
DISPLAY 0.723404 (-6050 5425);
PAINT MONO (-6050 5425);
DISPLAY INVISIBLE (-6050 5425);
FORCEPROP 1 LAST BODY_TYPE PLUMBING
J 2
(-6050 5475);
DISPLAY 0.872340 (-6050 5475);
PAINT GREEN (-6050 5475);
DISPLAY INVISIBLE (-6050 5475);
FORCEPROP 1 LAST HDL_TAP TRUE
J 2
(-6375 5300);
DISPLAY 0.872340 (-6375 5300);
DISPLAY INVISIBLE (-6375 5300);
FORCEPROP 1 LAST PATH I258
J 2
(-6048 5425);
DISPLAY 0.872340 (-6048 5425);
PAINT GREEN (-6048 5425);
DISPLAY INVISIBLE (-6048 5425);
FORCEADD TAP..1
R 2
(-6050 5325);
FORCEPROP 3 LASTPIN (-6000 5325) SIG_NAME M_E_CPU1_SA_DQS_DN<6>
J 0
(-5990 5335);
DISPLAY 0.659574 (-5990 5335);
PAINT MONO (-5990 5335);
DISPLAY INVISIBLE (-5990 5335);
FORCEPROP 1 LASTPIN (-6000 5325) BN 6
J 2
(-5988 5333);
DISPLAY 0.489362 (-5988 5333);
PAINT GREEN (-5988 5333);
FORCEPROP 2 LAST CDS_LIB mstr_standard
J 2
(-6050 5325);
DISPLAY 0.723404 (-6050 5325);
PAINT MONO (-6050 5325);
DISPLAY INVISIBLE (-6050 5325);
FORCEPROP 1 LAST BODY_TYPE PLUMBING
J 2
(-6050 5375);
DISPLAY 0.872340 (-6050 5375);
PAINT GREEN (-6050 5375);
DISPLAY INVISIBLE (-6050 5375);
FORCEPROP 1 LAST HDL_TAP TRUE
J 2
(-6375 5200);
DISPLAY 0.872340 (-6375 5200);
DISPLAY INVISIBLE (-6375 5200);
FORCEPROP 1 LAST PATH I259
J 2
(-6048 5325);
DISPLAY 0.872340 (-6048 5325);
PAINT GREEN (-6048 5325);
DISPLAY INVISIBLE (-6048 5325);
FORCEADD TAP..1
R 2
(-6050 5125);
FORCEPROP 3 LASTPIN (-6000 5125) SIG_NAME M_E_CPU1_SA_DQS_DN<8>
J 0
(-5990 5135);
DISPLAY 0.659574 (-5990 5135);
PAINT MONO (-5990 5135);
DISPLAY INVISIBLE (-5990 5135);
FORCEPROP 1 LASTPIN (-6000 5125) BN 8
J 2
(-5988 5133);
DISPLAY 0.489362 (-5988 5133);
PAINT GREEN (-5988 5133);
FORCEPROP 2 LAST CDS_LIB mstr_standard
J 2
(-6050 5125);
DISPLAY 0.723404 (-6050 5125);
PAINT MONO (-6050 5125);
DISPLAY INVISIBLE (-6050 5125);
FORCEPROP 1 LAST BODY_TYPE PLUMBING
J 2
(-6050 5175);
DISPLAY 0.872340 (-6050 5175);
PAINT GREEN (-6050 5175);
DISPLAY INVISIBLE (-6050 5175);
FORCEPROP 1 LAST HDL_TAP TRUE
J 2
(-6375 5000);
DISPLAY 0.872340 (-6375 5000);
DISPLAY INVISIBLE (-6375 5000);
FORCEPROP 1 LAST PATH I260
J 2
(-6048 5125);
DISPLAY 0.872340 (-6048 5125);
PAINT GREEN (-6048 5125);
DISPLAY INVISIBLE (-6048 5125);
FORCEADD TAP..1
R 2
(-6050 5225);
FORCEPROP 3 LASTPIN (-6000 5225) SIG_NAME M_E_CPU1_SA_DQS_DN<7>
J 0
(-5990 5235);
DISPLAY 0.659574 (-5990 5235);
PAINT MONO (-5990 5235);
DISPLAY INVISIBLE (-5990 5235);
FORCEPROP 1 LASTPIN (-6000 5225) BN 7
J 2
(-5988 5233);
DISPLAY 0.489362 (-5988 5233);
PAINT GREEN (-5988 5233);
FORCEPROP 2 LAST CDS_LIB mstr_standard
J 2
(-6050 5225);
DISPLAY 0.723404 (-6050 5225);
PAINT MONO (-6050 5225);
DISPLAY INVISIBLE (-6050 5225);
FORCEPROP 1 LAST BODY_TYPE PLUMBING
J 2
(-6050 5275);
DISPLAY 0.872340 (-6050 5275);
PAINT GREEN (-6050 5275);
DISPLAY INVISIBLE (-6050 5275);
FORCEPROP 1 LAST HDL_TAP TRUE
J 2
(-6375 5100);
DISPLAY 0.872340 (-6375 5100);
DISPLAY INVISIBLE (-6375 5100);
FORCEPROP 1 LAST PATH I261
J 2
(-6048 5225);
DISPLAY 0.872340 (-6048 5225);
PAINT GREEN (-6048 5225);
DISPLAY INVISIBLE (-6048 5225);
FORCEADD TAP..1
R 2
(-5850 4925);
FORCEPROP 3 LASTPIN (-5800 4925) SIG_NAME M_E_CPU1_SB_DQS_DP<0>
J 0
(-5790 4935);
DISPLAY 0.659574 (-5790 4935);
PAINT MONO (-5790 4935);
DISPLAY INVISIBLE (-5790 4935);
FORCEPROP 1 LASTPIN (-5800 4925) BN 0
J 2
(-5788 4933);
DISPLAY 0.489362 (-5788 4933);
PAINT GREEN (-5788 4933);
FORCEPROP 2 LAST CDS_LIB mstr_standard
J 2
(-5850 4925);
DISPLAY 0.723404 (-5850 4925);
PAINT MONO (-5850 4925);
DISPLAY INVISIBLE (-5850 4925);
FORCEPROP 1 LAST BODY_TYPE PLUMBING
J 2
(-5850 4975);
DISPLAY 0.872340 (-5850 4975);
PAINT GREEN (-5850 4975);
DISPLAY INVISIBLE (-5850 4975);
FORCEPROP 1 LAST HDL_TAP TRUE
J 2
(-6175 4800);
DISPLAY 0.872340 (-6175 4800);
DISPLAY INVISIBLE (-6175 4800);
FORCEPROP 1 LAST PATH I262
J 2
(-5848 4925);
DISPLAY 0.872340 (-5848 4925);
PAINT GREEN (-5848 4925);
DISPLAY INVISIBLE (-5848 4925);
FORCEADD TAP..1
R 2
(-5850 5075);
FORCEPROP 3 LASTPIN (-5800 5075) SIG_NAME M_E_CPU1_SA_DQS_DP<9>
J 0
(-5790 5085);
DISPLAY 0.659574 (-5790 5085);
PAINT MONO (-5790 5085);
DISPLAY INVISIBLE (-5790 5085);
FORCEPROP 1 LASTPIN (-5800 5075) BN 9
J 2
(-5788 5083);
DISPLAY 0.489362 (-5788 5083);
PAINT GREEN (-5788 5083);
FORCEPROP 2 LAST CDS_LIB mstr_standard
J 2
(-5850 5075);
DISPLAY 0.723404 (-5850 5075);
PAINT MONO (-5850 5075);
DISPLAY INVISIBLE (-5850 5075);
FORCEPROP 1 LAST BODY_TYPE PLUMBING
J 2
(-5850 5125);
DISPLAY 0.872340 (-5850 5125);
PAINT GREEN (-5850 5125);
DISPLAY INVISIBLE (-5850 5125);
FORCEPROP 1 LAST HDL_TAP TRUE
J 2
(-6175 4950);
DISPLAY 0.872340 (-6175 4950);
DISPLAY INVISIBLE (-6175 4950);
FORCEPROP 1 LAST PATH I263
J 2
(-5848 5075);
DISPLAY 0.872340 (-5848 5075);
PAINT GREEN (-5848 5075);
DISPLAY INVISIBLE (-5848 5075);
FORCEADD TAP..1
R 2
(-5850 4825);
FORCEPROP 3 LASTPIN (-5800 4825) SIG_NAME M_E_CPU1_SB_DQS_DP<1>
J 0
(-5790 4835);
DISPLAY 0.659574 (-5790 4835);
PAINT MONO (-5790 4835);
DISPLAY INVISIBLE (-5790 4835);
FORCEPROP 1 LASTPIN (-5800 4825) BN 1
J 2
(-5788 4833);
DISPLAY 0.489362 (-5788 4833);
PAINT GREEN (-5788 4833);
FORCEPROP 2 LAST CDS_LIB mstr_standard
J 2
(-5850 4825);
DISPLAY 0.723404 (-5850 4825);
PAINT MONO (-5850 4825);
DISPLAY INVISIBLE (-5850 4825);
FORCEPROP 1 LAST BODY_TYPE PLUMBING
J 2
(-5850 4875);
DISPLAY 0.872340 (-5850 4875);
PAINT GREEN (-5850 4875);
DISPLAY INVISIBLE (-5850 4875);
FORCEPROP 1 LAST HDL_TAP TRUE
J 2
(-6175 4700);
DISPLAY 0.872340 (-6175 4700);
DISPLAY INVISIBLE (-6175 4700);
FORCEPROP 1 LAST PATH I264
J 2
(-5848 4825);
DISPLAY 0.872340 (-5848 4825);
PAINT GREEN (-5848 4825);
DISPLAY INVISIBLE (-5848 4825);
FORCEADD TAP..1
R 2
(-5850 4725);
FORCEPROP 3 LASTPIN (-5800 4725) SIG_NAME M_E_CPU1_SB_DQS_DP<2>
J 0
(-5790 4735);
DISPLAY 0.659574 (-5790 4735);
PAINT MONO (-5790 4735);
DISPLAY INVISIBLE (-5790 4735);
FORCEPROP 1 LASTPIN (-5800 4725) BN 2
J 2
(-5788 4733);
DISPLAY 0.489362 (-5788 4733);
PAINT GREEN (-5788 4733);
FORCEPROP 2 LAST CDS_LIB mstr_standard
J 2
(-5850 4725);
DISPLAY 0.723404 (-5850 4725);
PAINT MONO (-5850 4725);
DISPLAY INVISIBLE (-5850 4725);
FORCEPROP 1 LAST BODY_TYPE PLUMBING
J 2
(-5850 4775);
DISPLAY 0.872340 (-5850 4775);
PAINT GREEN (-5850 4775);
DISPLAY INVISIBLE (-5850 4775);
FORCEPROP 1 LAST HDL_TAP TRUE
J 2
(-6175 4600);
DISPLAY 0.872340 (-6175 4600);
DISPLAY INVISIBLE (-6175 4600);
FORCEPROP 1 LAST PATH I265
J 2
(-5848 4725);
DISPLAY 0.872340 (-5848 4725);
PAINT GREEN (-5848 4725);
DISPLAY INVISIBLE (-5848 4725);
FORCEADD TAP..1
R 2
(-5850 4625);
FORCEPROP 3 LASTPIN (-5800 4625) SIG_NAME M_E_CPU1_SB_DQS_DP<3>
J 0
(-5790 4635);
DISPLAY 0.659574 (-5790 4635);
PAINT MONO (-5790 4635);
DISPLAY INVISIBLE (-5790 4635);
FORCEPROP 1 LASTPIN (-5800 4625) BN 3
J 2
(-5788 4633);
DISPLAY 0.489362 (-5788 4633);
PAINT GREEN (-5788 4633);
FORCEPROP 2 LAST CDS_LIB mstr_standard
J 2
(-5850 4625);
DISPLAY 0.723404 (-5850 4625);
PAINT MONO (-5850 4625);
DISPLAY INVISIBLE (-5850 4625);
FORCEPROP 1 LAST BODY_TYPE PLUMBING
J 2
(-5850 4675);
DISPLAY 0.872340 (-5850 4675);
PAINT GREEN (-5850 4675);
DISPLAY INVISIBLE (-5850 4675);
FORCEPROP 1 LAST HDL_TAP TRUE
J 2
(-6175 4500);
DISPLAY 0.872340 (-6175 4500);
DISPLAY INVISIBLE (-6175 4500);
FORCEPROP 1 LAST PATH I266
J 2
(-5848 4625);
DISPLAY 0.872340 (-5848 4625);
PAINT GREEN (-5848 4625);
DISPLAY INVISIBLE (-5848 4625);
FORCEADD TAP..1
R 2
(-6050 5025);
FORCEPROP 3 LASTPIN (-6000 5025) SIG_NAME M_E_CPU1_SA_DQS_DN<9>
J 0
(-5990 5035);
DISPLAY 0.659574 (-5990 5035);
PAINT MONO (-5990 5035);
DISPLAY INVISIBLE (-5990 5035);
FORCEPROP 1 LASTPIN (-6000 5025) BN 9
J 2
(-5988 5033);
DISPLAY 0.489362 (-5988 5033);
PAINT GREEN (-5988 5033);
FORCEPROP 2 LAST CDS_LIB mstr_standard
J 2
(-6050 5025);
DISPLAY 0.723404 (-6050 5025);
PAINT MONO (-6050 5025);
DISPLAY INVISIBLE (-6050 5025);
FORCEPROP 1 LAST BODY_TYPE PLUMBING
J 2
(-6050 5075);
DISPLAY 0.872340 (-6050 5075);
PAINT GREEN (-6050 5075);
DISPLAY INVISIBLE (-6050 5075);
FORCEPROP 1 LAST HDL_TAP TRUE
J 2
(-6375 4900);
DISPLAY 0.872340 (-6375 4900);
DISPLAY INVISIBLE (-6375 4900);
FORCEPROP 1 LAST PATH I267
J 2
(-6048 5025);
DISPLAY 0.872340 (-6048 5025);
PAINT GREEN (-6048 5025);
DISPLAY INVISIBLE (-6048 5025);
FORCEADD TAP..1
R 2
(-6050 4875);
FORCEPROP 3 LASTPIN (-6000 4875) SIG_NAME M_E_CPU1_SB_DQS_DN<0>
J 0
(-5990 4885);
DISPLAY 0.659574 (-5990 4885);
PAINT MONO (-5990 4885);
DISPLAY INVISIBLE (-5990 4885);
FORCEPROP 1 LASTPIN (-6000 4875) BN 0
J 2
(-5988 4883);
DISPLAY 0.489362 (-5988 4883);
PAINT GREEN (-5988 4883);
FORCEPROP 2 LAST CDS_LIB mstr_standard
J 2
(-6050 4875);
DISPLAY 0.723404 (-6050 4875);
PAINT MONO (-6050 4875);
DISPLAY INVISIBLE (-6050 4875);
FORCEPROP 1 LAST BODY_TYPE PLUMBING
J 2
(-6050 4925);
DISPLAY 0.872340 (-6050 4925);
PAINT GREEN (-6050 4925);
DISPLAY INVISIBLE (-6050 4925);
FORCEPROP 1 LAST HDL_TAP TRUE
J 2
(-6375 4750);
DISPLAY 0.872340 (-6375 4750);
DISPLAY INVISIBLE (-6375 4750);
FORCEPROP 1 LAST PATH I268
J 2
(-6048 4875);
DISPLAY 0.872340 (-6048 4875);
PAINT GREEN (-6048 4875);
DISPLAY INVISIBLE (-6048 4875);
FORCEADD TAP..1
R 2
(-6050 4775);
FORCEPROP 3 LASTPIN (-6000 4775) SIG_NAME M_E_CPU1_SB_DQS_DN<1>
J 0
(-5990 4785);
DISPLAY 0.659574 (-5990 4785);
PAINT MONO (-5990 4785);
DISPLAY INVISIBLE (-5990 4785);
FORCEPROP 1 LASTPIN (-6000 4775) BN 1
J 2
(-5988 4783);
DISPLAY 0.489362 (-5988 4783);
PAINT GREEN (-5988 4783);
FORCEPROP 2 LAST CDS_LIB mstr_standard
J 2
(-6050 4775);
DISPLAY 0.723404 (-6050 4775);
PAINT MONO (-6050 4775);
DISPLAY INVISIBLE (-6050 4775);
FORCEPROP 1 LAST BODY_TYPE PLUMBING
J 2
(-6050 4825);
DISPLAY 0.872340 (-6050 4825);
PAINT GREEN (-6050 4825);
DISPLAY INVISIBLE (-6050 4825);
FORCEPROP 1 LAST HDL_TAP TRUE
J 2
(-6375 4650);
DISPLAY 0.872340 (-6375 4650);
DISPLAY INVISIBLE (-6375 4650);
FORCEPROP 1 LAST PATH I269
J 2
(-6048 4775);
DISPLAY 0.872340 (-6048 4775);
PAINT GREEN (-6048 4775);
DISPLAY INVISIBLE (-6048 4775);
FORCEADD TAP..1
R 2
(-6050 4675);
FORCEPROP 3 LASTPIN (-6000 4675) SIG_NAME M_E_CPU1_SB_DQS_DN<2>
J 0
(-5990 4685);
DISPLAY 0.659574 (-5990 4685);
PAINT MONO (-5990 4685);
DISPLAY INVISIBLE (-5990 4685);
FORCEPROP 1 LASTPIN (-6000 4675) BN 2
J 2
(-5988 4683);
DISPLAY 0.489362 (-5988 4683);
PAINT GREEN (-5988 4683);
FORCEPROP 2 LAST CDS_LIB mstr_standard
J 2
(-6050 4675);
DISPLAY 0.723404 (-6050 4675);
PAINT MONO (-6050 4675);
DISPLAY INVISIBLE (-6050 4675);
FORCEPROP 1 LAST BODY_TYPE PLUMBING
J 2
(-6050 4725);
DISPLAY 0.872340 (-6050 4725);
PAINT GREEN (-6050 4725);
DISPLAY INVISIBLE (-6050 4725);
FORCEPROP 1 LAST HDL_TAP TRUE
J 2
(-6375 4550);
DISPLAY 0.872340 (-6375 4550);
DISPLAY INVISIBLE (-6375 4550);
FORCEPROP 1 LAST PATH I270
J 2
(-6048 4675);
DISPLAY 0.872340 (-6048 4675);
PAINT GREEN (-6048 4675);
DISPLAY INVISIBLE (-6048 4675);
FORCEADD TAP..1
R 2
(-5850 4425);
FORCEPROP 3 LASTPIN (-5800 4425) SIG_NAME M_E_CPU1_SB_DQS_DP<5>
J 0
(-5790 4435);
DISPLAY 0.659574 (-5790 4435);
PAINT MONO (-5790 4435);
DISPLAY INVISIBLE (-5790 4435);
FORCEPROP 1 LASTPIN (-5800 4425) BN 5
J 2
(-5788 4433);
DISPLAY 0.489362 (-5788 4433);
PAINT GREEN (-5788 4433);
FORCEPROP 2 LAST CDS_LIB mstr_standard
J 2
(-5850 4425);
DISPLAY 0.723404 (-5850 4425);
PAINT MONO (-5850 4425);
DISPLAY INVISIBLE (-5850 4425);
FORCEPROP 1 LAST BODY_TYPE PLUMBING
J 2
(-5850 4475);
DISPLAY 0.872340 (-5850 4475);
PAINT GREEN (-5850 4475);
DISPLAY INVISIBLE (-5850 4475);
FORCEPROP 1 LAST HDL_TAP TRUE
J 2
(-6175 4300);
DISPLAY 0.872340 (-6175 4300);
DISPLAY INVISIBLE (-6175 4300);
FORCEPROP 1 LAST PATH I271
J 2
(-5848 4425);
DISPLAY 0.872340 (-5848 4425);
PAINT GREEN (-5848 4425);
DISPLAY INVISIBLE (-5848 4425);
FORCEADD TAP..1
R 2
(-5850 4525);
FORCEPROP 3 LASTPIN (-5800 4525) SIG_NAME M_E_CPU1_SB_DQS_DP<4>
J 0
(-5790 4535);
DISPLAY 0.659574 (-5790 4535);
PAINT MONO (-5790 4535);
DISPLAY INVISIBLE (-5790 4535);
FORCEPROP 1 LASTPIN (-5800 4525) BN 4
J 2
(-5788 4533);
DISPLAY 0.489362 (-5788 4533);
PAINT GREEN (-5788 4533);
FORCEPROP 2 LAST CDS_LIB mstr_standard
J 2
(-5850 4525);
DISPLAY 0.723404 (-5850 4525);
PAINT MONO (-5850 4525);
DISPLAY INVISIBLE (-5850 4525);
FORCEPROP 1 LAST BODY_TYPE PLUMBING
J 2
(-5850 4575);
DISPLAY 0.872340 (-5850 4575);
PAINT GREEN (-5850 4575);
DISPLAY INVISIBLE (-5850 4575);
FORCEPROP 1 LAST HDL_TAP TRUE
J 2
(-6175 4400);
DISPLAY 0.872340 (-6175 4400);
DISPLAY INVISIBLE (-6175 4400);
FORCEPROP 1 LAST PATH I272
J 2
(-5848 4525);
DISPLAY 0.872340 (-5848 4525);
PAINT GREEN (-5848 4525);
DISPLAY INVISIBLE (-5848 4525);
FORCEADD TAP..1
R 2
(-5850 4325);
FORCEPROP 3 LASTPIN (-5800 4325) SIG_NAME M_E_CPU1_SB_DQS_DP<6>
J 0
(-5790 4335);
DISPLAY 0.659574 (-5790 4335);
PAINT MONO (-5790 4335);
DISPLAY INVISIBLE (-5790 4335);
FORCEPROP 1 LASTPIN (-5800 4325) BN 6
J 2
(-5788 4333);
DISPLAY 0.489362 (-5788 4333);
PAINT GREEN (-5788 4333);
FORCEPROP 2 LAST CDS_LIB mstr_standard
J 2
(-5850 4325);
DISPLAY 0.723404 (-5850 4325);
PAINT MONO (-5850 4325);
DISPLAY INVISIBLE (-5850 4325);
FORCEPROP 1 LAST BODY_TYPE PLUMBING
J 2
(-5850 4375);
DISPLAY 0.872340 (-5850 4375);
PAINT GREEN (-5850 4375);
DISPLAY INVISIBLE (-5850 4375);
FORCEPROP 1 LAST HDL_TAP TRUE
J 2
(-6175 4200);
DISPLAY 0.872340 (-6175 4200);
DISPLAY INVISIBLE (-6175 4200);
FORCEPROP 1 LAST PATH I273
J 2
(-5848 4325);
DISPLAY 0.872340 (-5848 4325);
PAINT GREEN (-5848 4325);
DISPLAY INVISIBLE (-5848 4325);
FORCEADD TAP..1
R 2
(-5850 4125);
FORCEPROP 3 LASTPIN (-5800 4125) SIG_NAME M_E_CPU1_SB_DQS_DP<8>
J 0
(-5790 4135);
DISPLAY 0.659574 (-5790 4135);
PAINT MONO (-5790 4135);
DISPLAY INVISIBLE (-5790 4135);
FORCEPROP 1 LASTPIN (-5800 4125) BN 8
J 2
(-5788 4133);
DISPLAY 0.489362 (-5788 4133);
PAINT GREEN (-5788 4133);
FORCEPROP 2 LAST CDS_LIB mstr_standard
J 2
(-5850 4125);
DISPLAY 0.723404 (-5850 4125);
PAINT MONO (-5850 4125);
DISPLAY INVISIBLE (-5850 4125);
FORCEPROP 1 LAST BODY_TYPE PLUMBING
J 2
(-5850 4175);
DISPLAY 0.872340 (-5850 4175);
PAINT GREEN (-5850 4175);
DISPLAY INVISIBLE (-5850 4175);
FORCEPROP 1 LAST HDL_TAP TRUE
J 2
(-6175 4000);
DISPLAY 0.872340 (-6175 4000);
DISPLAY INVISIBLE (-6175 4000);
FORCEPROP 1 LAST PATH I274
J 2
(-5848 4125);
DISPLAY 0.872340 (-5848 4125);
PAINT GREEN (-5848 4125);
DISPLAY INVISIBLE (-5848 4125);
FORCEADD TAP..1
R 2
(-5850 4225);
FORCEPROP 3 LASTPIN (-5800 4225) SIG_NAME M_E_CPU1_SB_DQS_DP<7>
J 0
(-5790 4235);
DISPLAY 0.659574 (-5790 4235);
PAINT MONO (-5790 4235);
DISPLAY INVISIBLE (-5790 4235);
FORCEPROP 1 LASTPIN (-5800 4225) BN 7
J 2
(-5788 4233);
DISPLAY 0.489362 (-5788 4233);
PAINT GREEN (-5788 4233);
FORCEPROP 2 LAST CDS_LIB mstr_standard
J 2
(-5850 4225);
DISPLAY 0.723404 (-5850 4225);
PAINT MONO (-5850 4225);
DISPLAY INVISIBLE (-5850 4225);
FORCEPROP 1 LAST BODY_TYPE PLUMBING
J 2
(-5850 4275);
DISPLAY 0.872340 (-5850 4275);
PAINT GREEN (-5850 4275);
DISPLAY INVISIBLE (-5850 4275);
FORCEPROP 1 LAST HDL_TAP TRUE
J 2
(-6175 4100);
DISPLAY 0.872340 (-6175 4100);
DISPLAY INVISIBLE (-6175 4100);
FORCEPROP 1 LAST PATH I275
J 2
(-5848 4225);
DISPLAY 0.872340 (-5848 4225);
PAINT GREEN (-5848 4225);
DISPLAY INVISIBLE (-5848 4225);
FORCEADD TAP..1
R 2
(-6050 4575);
FORCEPROP 3 LASTPIN (-6000 4575) SIG_NAME M_E_CPU1_SB_DQS_DN<3>
J 0
(-5990 4585);
DISPLAY 0.659574 (-5990 4585);
PAINT MONO (-5990 4585);
DISPLAY INVISIBLE (-5990 4585);
FORCEPROP 1 LASTPIN (-6000 4575) BN 3
J 2
(-5988 4583);
DISPLAY 0.489362 (-5988 4583);
PAINT GREEN (-5988 4583);
FORCEPROP 2 LAST CDS_LIB mstr_standard
J 2
(-6050 4575);
DISPLAY 0.723404 (-6050 4575);
PAINT MONO (-6050 4575);
DISPLAY INVISIBLE (-6050 4575);
FORCEPROP 1 LAST BODY_TYPE PLUMBING
J 2
(-6050 4625);
DISPLAY 0.872340 (-6050 4625);
PAINT GREEN (-6050 4625);
DISPLAY INVISIBLE (-6050 4625);
FORCEPROP 1 LAST HDL_TAP TRUE
J 2
(-6375 4450);
DISPLAY 0.872340 (-6375 4450);
DISPLAY INVISIBLE (-6375 4450);
FORCEPROP 1 LAST PATH I276
J 2
(-6048 4575);
DISPLAY 0.872340 (-6048 4575);
PAINT GREEN (-6048 4575);
DISPLAY INVISIBLE (-6048 4575);
FORCEADD TAP..1
R 2
(-6050 4475);
FORCEPROP 3 LASTPIN (-6000 4475) SIG_NAME M_E_CPU1_SB_DQS_DN<4>
J 0
(-5990 4485);
DISPLAY 0.659574 (-5990 4485);
PAINT MONO (-5990 4485);
DISPLAY INVISIBLE (-5990 4485);
FORCEPROP 1 LASTPIN (-6000 4475) BN 4
J 2
(-5988 4483);
DISPLAY 0.489362 (-5988 4483);
PAINT GREEN (-5988 4483);
FORCEPROP 2 LAST CDS_LIB mstr_standard
J 2
(-6050 4475);
DISPLAY 0.723404 (-6050 4475);
PAINT MONO (-6050 4475);
DISPLAY INVISIBLE (-6050 4475);
FORCEPROP 1 LAST BODY_TYPE PLUMBING
J 2
(-6050 4525);
DISPLAY 0.872340 (-6050 4525);
PAINT GREEN (-6050 4525);
DISPLAY INVISIBLE (-6050 4525);
FORCEPROP 1 LAST HDL_TAP TRUE
J 2
(-6375 4350);
DISPLAY 0.872340 (-6375 4350);
DISPLAY INVISIBLE (-6375 4350);
FORCEPROP 1 LAST PATH I277
J 2
(-6048 4475);
DISPLAY 0.872340 (-6048 4475);
PAINT GREEN (-6048 4475);
DISPLAY INVISIBLE (-6048 4475);
FORCEADD TAP..1
R 2
(-6050 4375);
FORCEPROP 3 LASTPIN (-6000 4375) SIG_NAME M_E_CPU1_SB_DQS_DN<5>
J 0
(-5990 4385);
DISPLAY 0.659574 (-5990 4385);
PAINT MONO (-5990 4385);
DISPLAY INVISIBLE (-5990 4385);
FORCEPROP 1 LASTPIN (-6000 4375) BN 5
J 2
(-5988 4383);
DISPLAY 0.489362 (-5988 4383);
PAINT GREEN (-5988 4383);
FORCEPROP 2 LAST CDS_LIB mstr_standard
J 2
(-6050 4375);
DISPLAY 0.723404 (-6050 4375);
PAINT MONO (-6050 4375);
DISPLAY INVISIBLE (-6050 4375);
FORCEPROP 1 LAST BODY_TYPE PLUMBING
J 2
(-6050 4425);
DISPLAY 0.872340 (-6050 4425);
PAINT GREEN (-6050 4425);
DISPLAY INVISIBLE (-6050 4425);
FORCEPROP 1 LAST HDL_TAP TRUE
J 2
(-6375 4250);
DISPLAY 0.872340 (-6375 4250);
DISPLAY INVISIBLE (-6375 4250);
FORCEPROP 1 LAST PATH I278
J 2
(-6048 4375);
DISPLAY 0.872340 (-6048 4375);
PAINT GREEN (-6048 4375);
DISPLAY INVISIBLE (-6048 4375);
FORCEADD TAP..1
R 2
(-6050 4275);
FORCEPROP 3 LASTPIN (-6000 4275) SIG_NAME M_E_CPU1_SB_DQS_DN<6>
J 0
(-5990 4285);
DISPLAY 0.659574 (-5990 4285);
PAINT MONO (-5990 4285);
DISPLAY INVISIBLE (-5990 4285);
FORCEPROP 1 LASTPIN (-6000 4275) BN 6
J 2
(-5988 4283);
DISPLAY 0.489362 (-5988 4283);
PAINT GREEN (-5988 4283);
FORCEPROP 2 LAST CDS_LIB mstr_standard
J 2
(-6050 4275);
DISPLAY 0.723404 (-6050 4275);
PAINT MONO (-6050 4275);
DISPLAY INVISIBLE (-6050 4275);
FORCEPROP 1 LAST BODY_TYPE PLUMBING
J 2
(-6050 4325);
DISPLAY 0.872340 (-6050 4325);
PAINT GREEN (-6050 4325);
DISPLAY INVISIBLE (-6050 4325);
FORCEPROP 1 LAST HDL_TAP TRUE
J 2
(-6375 4150);
DISPLAY 0.872340 (-6375 4150);
DISPLAY INVISIBLE (-6375 4150);
FORCEPROP 1 LAST PATH I279
J 2
(-6048 4275);
DISPLAY 0.872340 (-6048 4275);
PAINT GREEN (-6048 4275);
DISPLAY INVISIBLE (-6048 4275);
FORCEADD TAP..1
R 2
(-6050 4175);
FORCEPROP 3 LASTPIN (-6000 4175) SIG_NAME M_E_CPU1_SB_DQS_DN<7>
J 0
(-5990 4185);
DISPLAY 0.659574 (-5990 4185);
PAINT MONO (-5990 4185);
DISPLAY INVISIBLE (-5990 4185);
FORCEPROP 1 LASTPIN (-6000 4175) BN 7
J 2
(-5988 4183);
DISPLAY 0.489362 (-5988 4183);
PAINT GREEN (-5988 4183);
FORCEPROP 2 LAST CDS_LIB mstr_standard
J 2
(-6050 4175);
DISPLAY 0.723404 (-6050 4175);
PAINT MONO (-6050 4175);
DISPLAY INVISIBLE (-6050 4175);
FORCEPROP 1 LAST BODY_TYPE PLUMBING
J 2
(-6050 4225);
DISPLAY 0.872340 (-6050 4225);
PAINT GREEN (-6050 4225);
DISPLAY INVISIBLE (-6050 4225);
FORCEPROP 1 LAST HDL_TAP TRUE
J 2
(-6375 4050);
DISPLAY 0.872340 (-6375 4050);
DISPLAY INVISIBLE (-6375 4050);
FORCEPROP 1 LAST PATH I280
J 2
(-6048 4175);
DISPLAY 0.872340 (-6048 4175);
PAINT GREEN (-6048 4175);
DISPLAY INVISIBLE (-6048 4175);
FORCEADD OFFPAGE..3
R 2
(-6750 5950);
FORCEPROP 2 LAST $XR0 101 
J 0
(-7030 5950);
DISPLAY 0.638298 (-7030 5950);
PAINT MONO (-7030 5950);
FORCEPROP 2 LAST PATH I281
J 0
(-7025 6000);
DISPLAY 1.021277 (-7025 6000);
DISPLAY INVISIBLE (-7025 6000);
FORCEPROP 1 LAST COMMENT_BODY TRUE
J 2
(-6700 5850);
DISPLAY 0.872340 (-6700 5850);
PAINT GREEN (-6700 5850);
DISPLAY INVISIBLE (-6700 5850);
FORCEPROP 1 LAST OFFPAGE TRUE
J 2
(-7075 5825);
DISPLAY 0.872340 (-7075 5825);
PAINT GREEN (-7075 5825);
DISPLAY INVISIBLE (-7075 5825);
FORCEPROP 2 LAST CDS_LIB standard
J 0
(-6750 5950);
DISPLAY INVISIBLE (-6750 5950);
FORCEADD OFFPAGE..3
R 2
(-6750 6000);
FORCEPROP 2 LAST $XR0 101 
J 0
(-7030 6000);
DISPLAY 0.638298 (-7030 6000);
PAINT MONO (-7030 6000);
FORCEPROP 2 LAST PATH I282
J 0
(-7025 6050);
DISPLAY 1.021277 (-7025 6050);
DISPLAY INVISIBLE (-7025 6050);
FORCEPROP 1 LAST COMMENT_BODY TRUE
J 2
(-6700 5900);
DISPLAY 0.872340 (-6700 5900);
PAINT GREEN (-6700 5900);
DISPLAY INVISIBLE (-6700 5900);
FORCEPROP 1 LAST OFFPAGE TRUE
J 2
(-7075 5875);
DISPLAY 0.872340 (-7075 5875);
PAINT GREEN (-7075 5875);
DISPLAY INVISIBLE (-7075 5875);
FORCEPROP 2 LAST CDS_LIB standard
J 0
(-6750 6000);
DISPLAY INVISIBLE (-6750 6000);
FORCEADD OFFPAGE..3
R 2
(-6750 4900);
FORCEPROP 2 LAST $XR0 101 
J 0
(-7030 4900);
DISPLAY 0.638298 (-7030 4900);
PAINT MONO (-7030 4900);
FORCEPROP 2 LAST PATH I283
J 0
(-7025 4950);
DISPLAY 1.021277 (-7025 4950);
DISPLAY INVISIBLE (-7025 4950);
FORCEPROP 1 LAST COMMENT_BODY TRUE
J 2
(-6700 4800);
DISPLAY 0.872340 (-6700 4800);
PAINT GREEN (-6700 4800);
DISPLAY INVISIBLE (-6700 4800);
FORCEPROP 1 LAST OFFPAGE TRUE
J 2
(-7075 4775);
DISPLAY 0.872340 (-7075 4775);
PAINT GREEN (-7075 4775);
DISPLAY INVISIBLE (-7075 4775);
FORCEPROP 2 LAST CDS_LIB standard
J 0
(-6750 4900);
DISPLAY INVISIBLE (-6750 4900);
FORCEADD OFFPAGE..3
R 2
(-6750 4950);
FORCEPROP 2 LAST $XR0 101 
J 0
(-7030 4950);
DISPLAY 0.638298 (-7030 4950);
PAINT MONO (-7030 4950);
FORCEPROP 2 LAST PATH I284
J 0
(-7025 5000);
DISPLAY 1.021277 (-7025 5000);
DISPLAY INVISIBLE (-7025 5000);
FORCEPROP 1 LAST COMMENT_BODY TRUE
J 2
(-6700 4850);
DISPLAY 0.872340 (-6700 4850);
PAINT GREEN (-6700 4850);
DISPLAY INVISIBLE (-6700 4850);
FORCEPROP 1 LAST OFFPAGE TRUE
J 2
(-7075 4825);
DISPLAY 0.872340 (-7075 4825);
PAINT GREEN (-7075 4825);
DISPLAY INVISIBLE (-7075 4825);
FORCEPROP 2 LAST CDS_LIB standard
J 0
(-6750 4950);
DISPLAY INVISIBLE (-6750 4950);
FORCEADD TAP..1
R 2
(-5850 4025);
FORCEPROP 3 LASTPIN (-5800 4025) SIG_NAME M_E_CPU1_SB_DQS_DP<9>
J 0
(-5790 4035);
DISPLAY 0.659574 (-5790 4035);
PAINT MONO (-5790 4035);
DISPLAY INVISIBLE (-5790 4035);
FORCEPROP 1 LASTPIN (-5800 4025) BN 9
J 2
(-5788 4033);
DISPLAY 0.489362 (-5788 4033);
PAINT GREEN (-5788 4033);
FORCEPROP 2 LAST CDS_LIB mstr_standard
J 2
(-5850 4025);
DISPLAY 0.723404 (-5850 4025);
PAINT MONO (-5850 4025);
DISPLAY INVISIBLE (-5850 4025);
FORCEPROP 1 LAST BODY_TYPE PLUMBING
J 2
(-5850 4075);
DISPLAY 0.872340 (-5850 4075);
PAINT GREEN (-5850 4075);
DISPLAY INVISIBLE (-5850 4075);
FORCEPROP 1 LAST HDL_TAP TRUE
J 2
(-6175 3900);
DISPLAY 0.872340 (-6175 3900);
DISPLAY INVISIBLE (-6175 3900);
FORCEPROP 1 LAST PATH I285
J 2
(-5848 4025);
DISPLAY 0.872340 (-5848 4025);
PAINT GREEN (-5848 4025);
DISPLAY INVISIBLE (-5848 4025);
FORCEADD TAP..1
R 2
(-6050 4075);
FORCEPROP 3 LASTPIN (-6000 4075) SIG_NAME M_E_CPU1_SB_DQS_DN<8>
J 0
(-5990 4085);
DISPLAY 0.659574 (-5990 4085);
PAINT MONO (-5990 4085);
DISPLAY INVISIBLE (-5990 4085);
FORCEPROP 1 LASTPIN (-6000 4075) BN 8
J 2
(-5988 4083);
DISPLAY 0.489362 (-5988 4083);
PAINT GREEN (-5988 4083);
FORCEPROP 2 LAST CDS_LIB mstr_standard
J 2
(-6050 4075);
DISPLAY 0.723404 (-6050 4075);
PAINT MONO (-6050 4075);
DISPLAY INVISIBLE (-6050 4075);
FORCEPROP 1 LAST BODY_TYPE PLUMBING
J 2
(-6050 4125);
DISPLAY 0.872340 (-6050 4125);
PAINT GREEN (-6050 4125);
DISPLAY INVISIBLE (-6050 4125);
FORCEPROP 1 LAST HDL_TAP TRUE
J 2
(-6375 3950);
DISPLAY 0.872340 (-6375 3950);
DISPLAY INVISIBLE (-6375 3950);
FORCEPROP 1 LAST PATH I286
J 2
(-6048 4075);
DISPLAY 0.872340 (-6048 4075);
PAINT GREEN (-6048 4075);
DISPLAY INVISIBLE (-6048 4075);
FORCEADD TAP..1
R 2
(-6050 3975);
FORCEPROP 3 LASTPIN (-6000 3975) SIG_NAME M_E_CPU1_SB_DQS_DN<9>
J 0
(-5990 3985);
DISPLAY 0.659574 (-5990 3985);
PAINT MONO (-5990 3985);
DISPLAY INVISIBLE (-5990 3985);
FORCEPROP 1 LASTPIN (-6000 3975) BN 9
J 2
(-5988 3983);
DISPLAY 0.489362 (-5988 3983);
PAINT GREEN (-5988 3983);
FORCEPROP 2 LAST CDS_LIB mstr_standard
J 2
(-6050 3975);
DISPLAY 0.723404 (-6050 3975);
PAINT MONO (-6050 3975);
DISPLAY INVISIBLE (-6050 3975);
FORCEPROP 1 LAST BODY_TYPE PLUMBING
J 2
(-6050 4025);
DISPLAY 0.872340 (-6050 4025);
PAINT GREEN (-6050 4025);
DISPLAY INVISIBLE (-6050 4025);
FORCEPROP 1 LAST HDL_TAP TRUE
J 2
(-6375 3850);
DISPLAY 0.872340 (-6375 3850);
DISPLAY INVISIBLE (-6375 3850);
FORCEPROP 1 LAST PATH I287
J 2
(-6048 3975);
DISPLAY 0.872340 (-6048 3975);
PAINT GREEN (-6048 3975);
DISPLAY INVISIBLE (-6048 3975);
FORCEADD TAP..1
R 2
(-6050 3825);
FORCEPROP 3 LASTPIN (-6000 3825) SIG_NAME M_E_CPU1_SA_CA<0>
J 0
(-5990 3835);
DISPLAY 0.659574 (-5990 3835);
PAINT MONO (-5990 3835);
DISPLAY INVISIBLE (-5990 3835);
FORCEPROP 1 LASTPIN (-6000 3825) BN 0
J 2
(-5988 3833);
DISPLAY 0.489362 (-5988 3833);
PAINT GREEN (-5988 3833);
FORCEPROP 2 LAST CDS_LIB mstr_standard
J 0
(-6050 3825);
DISPLAY 0.723404 (-6050 3825);
PAINT MONO (-6050 3825);
DISPLAY INVISIBLE (-6050 3825);
FORCEPROP 1 LAST BODY_TYPE PLUMBING
J 2
(-6050 3875);
DISPLAY 0.872340 (-6050 3875);
PAINT GREEN (-6050 3875);
DISPLAY INVISIBLE (-6050 3875);
FORCEPROP 1 LAST HDL_TAP TRUE
J 2
(-6375 3700);
DISPLAY 0.872340 (-6375 3700);
DISPLAY INVISIBLE (-6375 3700);
FORCEPROP 1 LAST PATH I288
J 2
(-6048 3825);
DISPLAY 0.872340 (-6048 3825);
PAINT GREEN (-6048 3825);
DISPLAY INVISIBLE (-6048 3825);
FORCEADD TAP..1
R 2
(-6050 3775);
FORCEPROP 3 LASTPIN (-6000 3775) SIG_NAME M_E_CPU1_SA_CA<1>
J 0
(-5990 3785);
DISPLAY 0.659574 (-5990 3785);
PAINT MONO (-5990 3785);
DISPLAY INVISIBLE (-5990 3785);
FORCEPROP 1 LASTPIN (-6000 3775) BN 1
J 2
(-5988 3783);
DISPLAY 0.489362 (-5988 3783);
PAINT GREEN (-5988 3783);
FORCEPROP 2 LAST CDS_LIB mstr_standard
J 0
(-6050 3775);
DISPLAY 0.723404 (-6050 3775);
PAINT MONO (-6050 3775);
DISPLAY INVISIBLE (-6050 3775);
FORCEPROP 1 LAST BODY_TYPE PLUMBING
J 2
(-6050 3825);
DISPLAY 0.872340 (-6050 3825);
PAINT GREEN (-6050 3825);
DISPLAY INVISIBLE (-6050 3825);
FORCEPROP 1 LAST HDL_TAP TRUE
J 2
(-6375 3650);
DISPLAY 0.872340 (-6375 3650);
DISPLAY INVISIBLE (-6375 3650);
FORCEPROP 1 LAST PATH I289
J 2
(-6048 3775);
DISPLAY 0.872340 (-6048 3775);
PAINT GREEN (-6048 3775);
DISPLAY INVISIBLE (-6048 3775);
FORCEADD TAP..1
R 2
(-6050 3725);
FORCEPROP 3 LASTPIN (-6000 3725) SIG_NAME M_E_CPU1_SA_CA<2>
J 0
(-5990 3735);
DISPLAY 0.659574 (-5990 3735);
PAINT MONO (-5990 3735);
DISPLAY INVISIBLE (-5990 3735);
FORCEPROP 1 LASTPIN (-6000 3725) BN 2
J 2
(-5988 3733);
DISPLAY 0.489362 (-5988 3733);
PAINT GREEN (-5988 3733);
FORCEPROP 2 LAST CDS_LIB mstr_standard
J 0
(-6050 3725);
DISPLAY 0.723404 (-6050 3725);
PAINT MONO (-6050 3725);
DISPLAY INVISIBLE (-6050 3725);
FORCEPROP 1 LAST BODY_TYPE PLUMBING
J 2
(-6050 3775);
DISPLAY 0.872340 (-6050 3775);
PAINT GREEN (-6050 3775);
DISPLAY INVISIBLE (-6050 3775);
FORCEPROP 1 LAST HDL_TAP TRUE
J 2
(-6375 3600);
DISPLAY 0.872340 (-6375 3600);
DISPLAY INVISIBLE (-6375 3600);
FORCEPROP 1 LAST PATH I290
J 2
(-6048 3725);
DISPLAY 0.872340 (-6048 3725);
PAINT GREEN (-6048 3725);
DISPLAY INVISIBLE (-6048 3725);
FORCEADD TAP..1
R 2
(-6050 3675);
FORCEPROP 3 LASTPIN (-6000 3675) SIG_NAME M_E_CPU1_SA_CA<3>
J 0
(-5990 3685);
DISPLAY 0.659574 (-5990 3685);
PAINT MONO (-5990 3685);
DISPLAY INVISIBLE (-5990 3685);
FORCEPROP 1 LASTPIN (-6000 3675) BN 3
J 2
(-5988 3683);
DISPLAY 0.489362 (-5988 3683);
PAINT GREEN (-5988 3683);
FORCEPROP 2 LAST CDS_LIB mstr_standard
J 0
(-6050 3675);
DISPLAY 0.723404 (-6050 3675);
PAINT MONO (-6050 3675);
DISPLAY INVISIBLE (-6050 3675);
FORCEPROP 1 LAST BODY_TYPE PLUMBING
J 2
(-6050 3725);
DISPLAY 0.872340 (-6050 3725);
PAINT GREEN (-6050 3725);
DISPLAY INVISIBLE (-6050 3725);
FORCEPROP 1 LAST HDL_TAP TRUE
J 2
(-6375 3550);
DISPLAY 0.872340 (-6375 3550);
DISPLAY INVISIBLE (-6375 3550);
FORCEPROP 1 LAST PATH I291
J 2
(-6048 3675);
DISPLAY 0.872340 (-6048 3675);
PAINT GREEN (-6048 3675);
DISPLAY INVISIBLE (-6048 3675);
FORCEADD TAP..1
R 2
(-6050 3625);
FORCEPROP 3 LASTPIN (-6000 3625) SIG_NAME M_E_CPU1_SA_CA<4>
J 0
(-5990 3635);
DISPLAY 0.659574 (-5990 3635);
PAINT MONO (-5990 3635);
DISPLAY INVISIBLE (-5990 3635);
FORCEPROP 1 LASTPIN (-6000 3625) BN 4
J 2
(-5988 3633);
DISPLAY 0.489362 (-5988 3633);
PAINT GREEN (-5988 3633);
FORCEPROP 2 LAST CDS_LIB mstr_standard
J 0
(-6050 3625);
DISPLAY 0.723404 (-6050 3625);
PAINT MONO (-6050 3625);
DISPLAY INVISIBLE (-6050 3625);
FORCEPROP 1 LAST BODY_TYPE PLUMBING
J 2
(-6050 3675);
DISPLAY 0.872340 (-6050 3675);
PAINT GREEN (-6050 3675);
DISPLAY INVISIBLE (-6050 3675);
FORCEPROP 1 LAST HDL_TAP TRUE
J 2
(-6375 3500);
DISPLAY 0.872340 (-6375 3500);
DISPLAY INVISIBLE (-6375 3500);
FORCEPROP 1 LAST PATH I292
J 2
(-6048 3625);
DISPLAY 0.872340 (-6048 3625);
PAINT GREEN (-6048 3625);
DISPLAY INVISIBLE (-6048 3625);
FORCEADD TAP..1
R 2
(-6050 3575);
FORCEPROP 3 LASTPIN (-6000 3575) SIG_NAME M_E_CPU1_SA_CA<5>
J 0
(-5990 3585);
DISPLAY 0.659574 (-5990 3585);
PAINT MONO (-5990 3585);
DISPLAY INVISIBLE (-5990 3585);
FORCEPROP 1 LASTPIN (-6000 3575) BN 5
J 2
(-5988 3583);
DISPLAY 0.489362 (-5988 3583);
PAINT GREEN (-5988 3583);
FORCEPROP 2 LAST CDS_LIB mstr_standard
J 0
(-6050 3575);
DISPLAY 0.723404 (-6050 3575);
PAINT MONO (-6050 3575);
DISPLAY INVISIBLE (-6050 3575);
FORCEPROP 1 LAST BODY_TYPE PLUMBING
J 2
(-6050 3625);
DISPLAY 0.872340 (-6050 3625);
PAINT GREEN (-6050 3625);
DISPLAY INVISIBLE (-6050 3625);
FORCEPROP 1 LAST HDL_TAP TRUE
J 2
(-6375 3450);
DISPLAY 0.872340 (-6375 3450);
DISPLAY INVISIBLE (-6375 3450);
FORCEPROP 1 LAST PATH I293
J 2
(-6048 3575);
DISPLAY 0.872340 (-6048 3575);
PAINT GREEN (-6048 3575);
DISPLAY INVISIBLE (-6048 3575);
FORCEADD TAP..1
R 2
(-6050 3525);
FORCEPROP 3 LASTPIN (-6000 3525) SIG_NAME M_E_CPU1_SA_CA<6>
J 0
(-5990 3535);
DISPLAY 0.659574 (-5990 3535);
PAINT MONO (-5990 3535);
DISPLAY INVISIBLE (-5990 3535);
FORCEPROP 1 LASTPIN (-6000 3525) BN 6
J 2
(-5988 3533);
DISPLAY 0.489362 (-5988 3533);
PAINT GREEN (-5988 3533);
FORCEPROP 2 LAST CDS_LIB mstr_standard
J 0
(-6050 3525);
DISPLAY 0.723404 (-6050 3525);
PAINT MONO (-6050 3525);
DISPLAY INVISIBLE (-6050 3525);
FORCEPROP 1 LAST BODY_TYPE PLUMBING
J 2
(-6050 3575);
DISPLAY 0.872340 (-6050 3575);
PAINT GREEN (-6050 3575);
DISPLAY INVISIBLE (-6050 3575);
FORCEPROP 1 LAST HDL_TAP TRUE
J 2
(-6375 3400);
DISPLAY 0.872340 (-6375 3400);
DISPLAY INVISIBLE (-6375 3400);
FORCEPROP 1 LAST PATH I294
J 2
(-6048 3525);
DISPLAY 0.872340 (-6048 3525);
PAINT GREEN (-6048 3525);
DISPLAY INVISIBLE (-6048 3525);
FORCEADD TAP..1
R 2
(-6050 3425);
FORCEPROP 3 LASTPIN (-6000 3425) SIG_NAME M_E_CPU1_SB_CA<0>
J 0
(-5990 3435);
DISPLAY 0.659574 (-5990 3435);
PAINT MONO (-5990 3435);
DISPLAY INVISIBLE (-5990 3435);
FORCEPROP 1 LASTPIN (-6000 3425) BN 0
J 2
(-5988 3433);
DISPLAY 0.489362 (-5988 3433);
PAINT GREEN (-5988 3433);
FORCEPROP 2 LAST CDS_LIB mstr_standard
J 0
(-6050 3425);
DISPLAY 0.723404 (-6050 3425);
PAINT MONO (-6050 3425);
DISPLAY INVISIBLE (-6050 3425);
FORCEPROP 1 LAST BODY_TYPE PLUMBING
J 2
(-6050 3475);
DISPLAY 0.872340 (-6050 3475);
PAINT GREEN (-6050 3475);
DISPLAY INVISIBLE (-6050 3475);
FORCEPROP 1 LAST HDL_TAP TRUE
J 2
(-6375 3300);
DISPLAY 0.872340 (-6375 3300);
DISPLAY INVISIBLE (-6375 3300);
FORCEPROP 1 LAST PATH I295
J 2
(-6048 3425);
DISPLAY 0.872340 (-6048 3425);
PAINT GREEN (-6048 3425);
DISPLAY INVISIBLE (-6048 3425);
FORCEADD TAP..1
R 2
(-6050 3375);
FORCEPROP 3 LASTPIN (-6000 3375) SIG_NAME M_E_CPU1_SB_CA<1>
J 0
(-5990 3385);
DISPLAY 0.659574 (-5990 3385);
PAINT MONO (-5990 3385);
DISPLAY INVISIBLE (-5990 3385);
FORCEPROP 1 LASTPIN (-6000 3375) BN 1
J 2
(-5988 3383);
DISPLAY 0.489362 (-5988 3383);
PAINT GREEN (-5988 3383);
FORCEPROP 2 LAST CDS_LIB mstr_standard
J 0
(-6050 3375);
DISPLAY 0.723404 (-6050 3375);
PAINT MONO (-6050 3375);
DISPLAY INVISIBLE (-6050 3375);
FORCEPROP 1 LAST BODY_TYPE PLUMBING
J 2
(-6050 3425);
DISPLAY 0.872340 (-6050 3425);
PAINT GREEN (-6050 3425);
DISPLAY INVISIBLE (-6050 3425);
FORCEPROP 1 LAST HDL_TAP TRUE
J 2
(-6375 3250);
DISPLAY 0.872340 (-6375 3250);
DISPLAY INVISIBLE (-6375 3250);
FORCEPROP 1 LAST PATH I296
J 2
(-6048 3375);
DISPLAY 0.872340 (-6048 3375);
PAINT GREEN (-6048 3375);
DISPLAY INVISIBLE (-6048 3375);
FORCEADD TAP..1
R 2
(-6050 3325);
FORCEPROP 3 LASTPIN (-6000 3325) SIG_NAME M_E_CPU1_SB_CA<2>
J 0
(-5990 3335);
DISPLAY 0.659574 (-5990 3335);
PAINT MONO (-5990 3335);
DISPLAY INVISIBLE (-5990 3335);
FORCEPROP 1 LASTPIN (-6000 3325) BN 2
J 2
(-5988 3333);
DISPLAY 0.489362 (-5988 3333);
PAINT GREEN (-5988 3333);
FORCEPROP 2 LAST CDS_LIB mstr_standard
J 0
(-6050 3325);
DISPLAY 0.723404 (-6050 3325);
PAINT MONO (-6050 3325);
DISPLAY INVISIBLE (-6050 3325);
FORCEPROP 1 LAST BODY_TYPE PLUMBING
J 2
(-6050 3375);
DISPLAY 0.872340 (-6050 3375);
PAINT GREEN (-6050 3375);
DISPLAY INVISIBLE (-6050 3375);
FORCEPROP 1 LAST HDL_TAP TRUE
J 2
(-6375 3200);
DISPLAY 0.872340 (-6375 3200);
DISPLAY INVISIBLE (-6375 3200);
FORCEPROP 1 LAST PATH I297
J 2
(-6048 3325);
DISPLAY 0.872340 (-6048 3325);
PAINT GREEN (-6048 3325);
DISPLAY INVISIBLE (-6048 3325);
FORCEADD TAP..1
R 2
(-6050 3275);
FORCEPROP 3 LASTPIN (-6000 3275) SIG_NAME M_E_CPU1_SB_CA<3>
J 0
(-5990 3285);
DISPLAY 0.659574 (-5990 3285);
PAINT MONO (-5990 3285);
DISPLAY INVISIBLE (-5990 3285);
FORCEPROP 1 LASTPIN (-6000 3275) BN 3
J 2
(-5988 3283);
DISPLAY 0.489362 (-5988 3283);
PAINT GREEN (-5988 3283);
FORCEPROP 2 LAST CDS_LIB mstr_standard
J 0
(-6050 3275);
DISPLAY 0.723404 (-6050 3275);
PAINT MONO (-6050 3275);
DISPLAY INVISIBLE (-6050 3275);
FORCEPROP 1 LAST BODY_TYPE PLUMBING
J 2
(-6050 3325);
DISPLAY 0.872340 (-6050 3325);
PAINT GREEN (-6050 3325);
DISPLAY INVISIBLE (-6050 3325);
FORCEPROP 1 LAST HDL_TAP TRUE
J 2
(-6375 3150);
DISPLAY 0.872340 (-6375 3150);
DISPLAY INVISIBLE (-6375 3150);
FORCEPROP 1 LAST PATH I298
J 2
(-6048 3275);
DISPLAY 0.872340 (-6048 3275);
PAINT GREEN (-6048 3275);
DISPLAY INVISIBLE (-6048 3275);
FORCEADD TAP..1
R 2
(-6050 3225);
FORCEPROP 3 LASTPIN (-6000 3225) SIG_NAME M_E_CPU1_SB_CA<4>
J 0
(-5990 3235);
DISPLAY 0.659574 (-5990 3235);
PAINT MONO (-5990 3235);
DISPLAY INVISIBLE (-5990 3235);
FORCEPROP 1 LASTPIN (-6000 3225) BN 4
J 2
(-5988 3233);
DISPLAY 0.489362 (-5988 3233);
PAINT GREEN (-5988 3233);
FORCEPROP 2 LAST CDS_LIB mstr_standard
J 0
(-6050 3225);
DISPLAY 0.723404 (-6050 3225);
PAINT MONO (-6050 3225);
DISPLAY INVISIBLE (-6050 3225);
FORCEPROP 1 LAST BODY_TYPE PLUMBING
J 2
(-6050 3275);
DISPLAY 0.872340 (-6050 3275);
PAINT GREEN (-6050 3275);
DISPLAY INVISIBLE (-6050 3275);
FORCEPROP 1 LAST HDL_TAP TRUE
J 2
(-6375 3100);
DISPLAY 0.872340 (-6375 3100);
DISPLAY INVISIBLE (-6375 3100);
FORCEPROP 1 LAST PATH I299
J 2
(-6048 3225);
DISPLAY 0.872340 (-6048 3225);
PAINT GREEN (-6048 3225);
DISPLAY INVISIBLE (-6048 3225);
FORCEADD TAP..1
R 2
(-6050 3125);
FORCEPROP 3 LASTPIN (-6000 3125) SIG_NAME M_E_CPU1_SB_CA<6>
J 0
(-5990 3135);
DISPLAY 0.659574 (-5990 3135);
PAINT MONO (-5990 3135);
DISPLAY INVISIBLE (-5990 3135);
FORCEPROP 1 LASTPIN (-6000 3125) BN 6
J 2
(-5988 3133);
DISPLAY 0.489362 (-5988 3133);
PAINT GREEN (-5988 3133);
FORCEPROP 2 LAST CDS_LIB mstr_standard
J 0
(-6050 3125);
DISPLAY 0.723404 (-6050 3125);
PAINT MONO (-6050 3125);
DISPLAY INVISIBLE (-6050 3125);
FORCEPROP 1 LAST BODY_TYPE PLUMBING
J 2
(-6050 3175);
DISPLAY 0.872340 (-6050 3175);
PAINT GREEN (-6050 3175);
DISPLAY INVISIBLE (-6050 3175);
FORCEPROP 1 LAST HDL_TAP TRUE
J 2
(-6375 3000);
DISPLAY 0.872340 (-6375 3000);
DISPLAY INVISIBLE (-6375 3000);
FORCEPROP 1 LAST PATH I300
J 2
(-6048 3125);
DISPLAY 0.872340 (-6048 3125);
PAINT GREEN (-6048 3125);
DISPLAY INVISIBLE (-6048 3125);
FORCEADD TAP..1
R 2
(-6050 3175);
FORCEPROP 3 LASTPIN (-6000 3175) SIG_NAME M_E_CPU1_SB_CA<5>
J 0
(-5990 3185);
DISPLAY 0.659574 (-5990 3185);
PAINT MONO (-5990 3185);
DISPLAY INVISIBLE (-5990 3185);
FORCEPROP 1 LASTPIN (-6000 3175) BN 5
J 2
(-5988 3183);
DISPLAY 0.489362 (-5988 3183);
PAINT GREEN (-5988 3183);
FORCEPROP 2 LAST CDS_LIB mstr_standard
J 0
(-6050 3175);
DISPLAY 0.723404 (-6050 3175);
PAINT MONO (-6050 3175);
DISPLAY INVISIBLE (-6050 3175);
FORCEPROP 1 LAST BODY_TYPE PLUMBING
J 2
(-6050 3225);
DISPLAY 0.872340 (-6050 3225);
PAINT GREEN (-6050 3225);
DISPLAY INVISIBLE (-6050 3225);
FORCEPROP 1 LAST HDL_TAP TRUE
J 2
(-6375 3050);
DISPLAY 0.872340 (-6375 3050);
DISPLAY INVISIBLE (-6375 3050);
FORCEPROP 1 LAST PATH I301
J 2
(-6048 3175);
DISPLAY 0.872340 (-6048 3175);
PAINT GREEN (-6048 3175);
DISPLAY INVISIBLE (-6048 3175);
FORCEADD OFFPAGE..2
R 2
(-6650 3850);
FORCEPROP 2 LAST $XR0 101 
J 0
(-6905 3850);
DISPLAY 0.638298 (-6905 3850);
PAINT MONO (-6905 3850);
FORCEPROP 2 LAST PATH I302
J 0
(-6900 3900);
DISPLAY 1.021277 (-6900 3900);
DISPLAY INVISIBLE (-6900 3900);
FORCEPROP 1 LAST COMMENT_BODY TRUE
J 2
(-6605 3755);
DISPLAY 0.872340 (-6605 3755);
PAINT GREEN (-6605 3755);
DISPLAY INVISIBLE (-6605 3755);
FORCEPROP 1 LAST OFFPAGE TRUE
J 2
(-6975 3725);
DISPLAY 0.872340 (-6975 3725);
PAINT GREEN (-6975 3725);
DISPLAY INVISIBLE (-6975 3725);
FORCEPROP 2 LAST CDS_LIB standard
J 0
(-6650 3850);
DISPLAY INVISIBLE (-6650 3850);
FORCEADD OFFPAGE..2
R 2
(-6650 3450);
FORCEPROP 2 LAST $XR0 101 
J 0
(-6905 3450);
DISPLAY 0.638298 (-6905 3450);
PAINT MONO (-6905 3450);
FORCEPROP 2 LAST PATH I303
J 0
(-6900 3500);
DISPLAY 1.021277 (-6900 3500);
DISPLAY INVISIBLE (-6900 3500);
FORCEPROP 1 LAST COMMENT_BODY TRUE
J 2
(-6605 3355);
DISPLAY 0.872340 (-6605 3355);
PAINT GREEN (-6605 3355);
DISPLAY INVISIBLE (-6605 3355);
FORCEPROP 1 LAST OFFPAGE TRUE
J 2
(-6975 3325);
DISPLAY 0.872340 (-6975 3325);
PAINT GREEN (-6975 3325);
DISPLAY INVISIBLE (-6975 3325);
FORCEPROP 2 LAST CDS_LIB standard
J 0
(-6650 3450);
DISPLAY INVISIBLE (-6650 3450);
FORCEADD OFFPAGE..2
R 2
(-6650 2975);
FORCEPROP 2 LAST $XR0 101 
J 0
(-6905 2975);
DISPLAY 0.638298 (-6905 2975);
PAINT MONO (-6905 2975);
FORCEPROP 2 LAST PATH I304
J 0
(-6900 3025);
DISPLAY 1.021277 (-6900 3025);
DISPLAY INVISIBLE (-6900 3025);
FORCEPROP 1 LAST COMMENT_BODY TRUE
J 2
(-6605 2880);
DISPLAY 0.872340 (-6605 2880);
PAINT GREEN (-6605 2880);
DISPLAY INVISIBLE (-6605 2880);
FORCEPROP 1 LAST OFFPAGE TRUE
J 2
(-6975 2850);
DISPLAY 0.872340 (-6975 2850);
PAINT GREEN (-6975 2850);
DISPLAY INVISIBLE (-6975 2850);
FORCEPROP 2 LAST CDS_LIB standard
J 0
(-6650 2975);
DISPLAY INVISIBLE (-6650 2975);
FORCEADD OFFPAGE..2
R 2
(-6650 2925);
FORCEPROP 2 LAST $XR0 101 
J 0
(-6905 2925);
DISPLAY 0.638298 (-6905 2925);
PAINT MONO (-6905 2925);
FORCEPROP 2 LAST PATH I305
J 0
(-6900 2975);
DISPLAY 1.021277 (-6900 2975);
DISPLAY INVISIBLE (-6900 2975);
FORCEPROP 1 LAST COMMENT_BODY TRUE
J 2
(-6605 2830);
DISPLAY 0.872340 (-6605 2830);
PAINT GREEN (-6605 2830);
DISPLAY INVISIBLE (-6605 2830);
FORCEPROP 1 LAST OFFPAGE TRUE
J 2
(-6975 2800);
DISPLAY 0.872340 (-6975 2800);
PAINT GREEN (-6975 2800);
DISPLAY INVISIBLE (-6975 2800);
FORCEPROP 2 LAST CDS_LIB standard
J 0
(-6650 2925);
DISPLAY INVISIBLE (-6650 2925);
FORCEADD OFFPAGE..2
R 2
(-6650 2825);
FORCEPROP 2 LAST $XR0 101 
J 0
(-6905 2825);
DISPLAY 0.638298 (-6905 2825);
PAINT MONO (-6905 2825);
FORCEPROP 2 LAST PATH I306
J 0
(-6900 2875);
DISPLAY 1.021277 (-6900 2875);
DISPLAY INVISIBLE (-6900 2875);
FORCEPROP 1 LAST COMMENT_BODY TRUE
J 2
(-6605 2730);
DISPLAY 0.872340 (-6605 2730);
PAINT GREEN (-6605 2730);
DISPLAY INVISIBLE (-6605 2730);
FORCEPROP 1 LAST OFFPAGE TRUE
J 2
(-6975 2700);
DISPLAY 0.872340 (-6975 2700);
PAINT GREEN (-6975 2700);
DISPLAY INVISIBLE (-6975 2700);
FORCEPROP 2 LAST CDS_LIB standard
J 0
(-6650 2825);
DISPLAY INVISIBLE (-6650 2825);
FORCEADD OFFPAGE..1
(-6650 2675);
FORCEPROP 2 LAST $XR0 101 
J 0
(-6902 2675);
DISPLAY 0.638298 (-6902 2675);
PAINT MONO (-6902 2675);
FORCEPROP 2 LAST PATH I307
J 0
(-6925 2725);
DISPLAY 1.021277 (-6925 2725);
DISPLAY INVISIBLE (-6925 2725);
FORCEPROP 1 LAST COMMENT_BODY TRUE
J 0
(-6525 2575);
DISPLAY 0.872340 (-6525 2575);
PAINT GREEN (-6525 2575);
DISPLAY INVISIBLE (-6525 2575);
FORCEPROP 1 LAST OFFPAGE TRUE
J 0
(-6325 2550);
DISPLAY 0.872340 (-6325 2550);
PAINT GREEN (-6325 2550);
DISPLAY INVISIBLE (-6325 2550);
FORCEPROP 2 LAST CDS_LIB standard
J 0
(-6650 2675);
DISPLAY INVISIBLE (-6650 2675);
FORCEADD OFFPAGE..2
R 2
(-6650 2775);
FORCEPROP 2 LAST $XR0 101 
J 0
(-6905 2775);
DISPLAY 0.638298 (-6905 2775);
PAINT MONO (-6905 2775);
FORCEPROP 2 LAST PATH I308
J 0
(-6900 2825);
DISPLAY 1.021277 (-6900 2825);
DISPLAY INVISIBLE (-6900 2825);
FORCEPROP 1 LAST COMMENT_BODY TRUE
J 2
(-6605 2680);
DISPLAY 0.872340 (-6605 2680);
PAINT GREEN (-6605 2680);
DISPLAY INVISIBLE (-6605 2680);
FORCEPROP 1 LAST OFFPAGE TRUE
J 2
(-6975 2650);
DISPLAY 0.872340 (-6975 2650);
PAINT GREEN (-6975 2650);
DISPLAY INVISIBLE (-6975 2650);
FORCEPROP 2 LAST CDS_LIB standard
J 0
(-6650 2775);
DISPLAY INVISIBLE (-6650 2775);
FORCEADD OFFPAGE..5
(-6650 2575);
FORCEPROP 2 LAST $XR0 101 
J 0
(-6905 2575);
DISPLAY 0.638298 (-6905 2575);
PAINT MONO (-6905 2575);
FORCEPROP 2 LAST PATH I309
J 0
(-6900 2625);
DISPLAY 1.021277 (-6900 2625);
DISPLAY INVISIBLE (-6900 2625);
FORCEPROP 1 LAST COMMENT_BODY TRUE
J 0
(-6550 2500);
DISPLAY 0.872340 (-6550 2500);
PAINT GREEN (-6550 2500);
DISPLAY INVISIBLE (-6550 2500);
FORCEPROP 1 LAST OFFPAGE TRUE
J 0
(-6325 2450);
DISPLAY 0.872340 (-6325 2450);
PAINT GREEN (-6325 2450);
DISPLAY INVISIBLE (-6325 2450);
FORCEPROP 2 LAST CDS_LIB mstr_standard
J 0
(-6650 2575);
DISPLAY INVISIBLE (-6650 2575);
FORCEADD OFFPAGE..2
R 2
(-6650 2425);
FORCEPROP 2 LAST $XR0 101 
J 0
(-6905 2425);
DISPLAY 0.638298 (-6905 2425);
PAINT MONO (-6905 2425);
FORCEPROP 2 LAST PATH I310
J 0
(-6900 2475);
DISPLAY 1.021277 (-6900 2475);
DISPLAY INVISIBLE (-6900 2475);
FORCEPROP 1 LAST COMMENT_BODY TRUE
J 2
(-6605 2330);
DISPLAY 0.872340 (-6605 2330);
PAINT GREEN (-6605 2330);
DISPLAY INVISIBLE (-6605 2330);
FORCEPROP 1 LAST OFFPAGE TRUE
J 2
(-6975 2300);
DISPLAY 0.872340 (-6975 2300);
PAINT GREEN (-6975 2300);
DISPLAY INVISIBLE (-6975 2300);
FORCEPROP 2 LAST CDS_LIB standard
J 0
(-6650 2425);
DISPLAY INVISIBLE (-6650 2425);
FORCEADD OFFPAGE..2
R 2
(-6650 2475);
FORCEPROP 2 LAST $XR0 101 
J 0
(-6905 2475);
DISPLAY 0.638298 (-6905 2475);
PAINT MONO (-6905 2475);
FORCEPROP 2 LAST PATH I311
J 0
(-6900 2525);
DISPLAY 1.021277 (-6900 2525);
DISPLAY INVISIBLE (-6900 2525);
FORCEPROP 1 LAST COMMENT_BODY TRUE
J 2
(-6605 2380);
DISPLAY 0.872340 (-6605 2380);
PAINT GREEN (-6605 2380);
DISPLAY INVISIBLE (-6605 2380);
FORCEPROP 1 LAST OFFPAGE TRUE
J 2
(-6975 2350);
DISPLAY 0.872340 (-6975 2350);
PAINT GREEN (-6975 2350);
DISPLAY INVISIBLE (-6975 2350);
FORCEPROP 2 LAST CDS_LIB standard
J 0
(-6650 2475);
DISPLAY INVISIBLE (-6650 2475);
FORCEADD OFFPAGE..1
(-6650 2325);
FORCEPROP 2 LAST $XR0 101 
J 0
(-6902 2325);
DISPLAY 0.638298 (-6902 2325);
PAINT MONO (-6902 2325);
FORCEPROP 2 LAST PATH I312
J 0
(-6925 2375);
DISPLAY 1.021277 (-6925 2375);
DISPLAY INVISIBLE (-6925 2375);
FORCEPROP 1 LAST COMMENT_BODY TRUE
J 0
(-6525 2225);
DISPLAY 0.872340 (-6525 2225);
PAINT GREEN (-6525 2225);
DISPLAY INVISIBLE (-6525 2225);
FORCEPROP 1 LAST OFFPAGE TRUE
J 0
(-6325 2200);
DISPLAY 0.872340 (-6325 2200);
PAINT GREEN (-6325 2200);
DISPLAY INVISIBLE (-6325 2200);
FORCEPROP 2 LAST CDS_LIB standard
J 0
(-6650 2325);
DISPLAY INVISIBLE (-6650 2325);
FORCEADD OFFPAGE..5
(-6650 2225);
FORCEPROP 2 LAST $XR0 101 
J 0
(-6905 2225);
DISPLAY 0.638298 (-6905 2225);
PAINT MONO (-6905 2225);
FORCEPROP 2 LAST PATH I313
J 0
(-6900 2275);
DISPLAY 1.021277 (-6900 2275);
DISPLAY INVISIBLE (-6900 2275);
FORCEPROP 1 LAST COMMENT_BODY TRUE
J 0
(-6550 2150);
DISPLAY 0.872340 (-6550 2150);
PAINT GREEN (-6550 2150);
DISPLAY INVISIBLE (-6550 2150);
FORCEPROP 1 LAST OFFPAGE TRUE
J 0
(-6325 2100);
DISPLAY 0.872340 (-6325 2100);
PAINT GREEN (-6325 2100);
DISPLAY INVISIBLE (-6325 2100);
FORCEPROP 2 LAST CDS_LIB standard
J 0
(-6650 2225);
DISPLAY INVISIBLE (-6650 2225);
FORCEADD Q_RES..1
(-6725 2125);
FORCEPROP 1 LAST LOCATION R504
J 0
(-7050 2125);
DISPLAY 0.489362 (-7050 2125);
PAINT SKYBLUE (-7050 2125);
FORCEPROP 0 LAST $SEC 1
J 0
(-6900 2175);
DISPLAY 0.680851 (-6900 2175);
PAINT MONO (-6900 2175);
DISPLAY INVISIBLE (-6900 2175);
FORCEPROP 0 LAST CDS_SEC 1
J 0
(-6900 2175);
DISPLAY 1.021277 (-6900 2175);
DISPLAY INVISIBLE (-6900 2175);
FORCEPROP 1 LASTPIN (-6825 2125) $PN 1
J 0
(-6813 2137);
DISPLAY 0.489362 (-6813 2137);
PAINT MONO (-6813 2137);
FORCEPROP 1 LASTPIN (-6625 2125) $PN 2
J 0
(-6663 2137);
DISPLAY 0.489362 (-6663 2137);
PAINT MONO (-6663 2137);
FORCEPROP 1 LAST TOLERANCE 1%
J 0
(-6450 2125);
DISPLAY 0.489362 (-6450 2125);
PAINT SKYBLUE (-6450 2125);
FORCEPROP 1 LAST VALUE 15   
J 2
(-6400 2125);
DISPLAY 0.489362 (-6400 2125);
PAINT SKYBLUE (-6400 2125);
FORCEPROP 1 LAST PART_NUMBER CS01502FB11
J 0
(-6600 2100);
DISPLAY 0.489362 (-6600 2100);
PAINT SKYBLUE (-6600 2100);
FORCEPROP 1 LAST PACK_TYPE 0402LF
J 0
(-7050 2100);
DISPLAY 0.489362 (-7050 2100);
PAINT SKYBLUE (-7050 2100);
FORCEPROP 2 LAST CDS_LIB pure_quanta
J 0
(-6725 2125);
DISPLAY INVISIBLE (-6725 2125);
FORCEPROP 1 LAST PATH I314
J 0
(-6775 2275);
DISPLAY 0.978723 (-6775 2275);
PAINT WHITE (-6775 2275);
DISPLAY INVISIBLE (-6775 2275);
FORCEPROP 1 LAST WATTAGE 1/16W
J 2
(-6500 2250);
DISPLAY 0.638298 (-6500 2250);
PAINT SKYBLUE (-6500 2250);
DISPLAY INVISIBLE (-6500 2250);
FORCEPROP 1 LAST MATERIAL CHIP
J 0
(-6850 2250);
DISPLAY 0.638298 (-6850 2250);
PAINT SKYBLUE (-6850 2250);
DISPLAY INVISIBLE (-6850 2250);
FORCEADD OFFPAGE..1
(-7600 2125);
FORCEPROP 2 LAST $XR0 101 
J 0
(-7852 2125);
DISPLAY 0.638298 (-7852 2125);
PAINT MONO (-7852 2125);
FORCEPROP 2 LAST PATH I315
J 0
(-7850 2175);
DISPLAY 1.021277 (-7850 2175);
DISPLAY INVISIBLE (-7850 2175);
FORCEPROP 1 LAST COMMENT_BODY TRUE
J 0
(-7475 2025);
DISPLAY 0.872340 (-7475 2025);
PAINT GREEN (-7475 2025);
DISPLAY INVISIBLE (-7475 2025);
FORCEPROP 1 LAST OFFPAGE TRUE
J 0
(-7275 2000);
DISPLAY 0.872340 (-7275 2000);
PAINT GREEN (-7275 2000);
DISPLAY INVISIBLE (-7275 2000);
FORCEPROP 2 LAST CDS_LIB mstr_standard
J 0
(-7600 2125);
DISPLAY INVISIBLE (-7600 2125);
FORCEADD OFFPAGE..5
(-6650 2025);
FORCEPROP 2 LAST $XR0 101 
J 0
(-6905 2025);
DISPLAY 0.638298 (-6905 2025);
PAINT MONO (-6905 2025);
FORCEPROP 2 LAST PATH I316
J 0
(-6900 2075);
DISPLAY 1.021277 (-6900 2075);
DISPLAY INVISIBLE (-6900 2075);
FORCEPROP 1 LAST COMMENT_BODY TRUE
J 0
(-6550 1950);
DISPLAY 0.872340 (-6550 1950);
PAINT GREEN (-6550 1950);
DISPLAY INVISIBLE (-6550 1950);
FORCEPROP 1 LAST OFFPAGE TRUE
J 0
(-6325 1900);
DISPLAY 0.872340 (-6325 1900);
PAINT GREEN (-6325 1900);
DISPLAY INVISIBLE (-6325 1900);
FORCEPROP 2 LAST CDS_LIB standard
J 0
(-6650 2025);
DISPLAY INVISIBLE (-6650 2025);
FORCEADD CAD_NOTE..1
(-7800 2400);
FORCEPROP 0 LAST L1 R1962 PLACE CLOSE TO CPU < 25MM
J 0
(-7950 2275);
DISPLAY 0.617021 (-7950 2275);
PAINT WHITE (-7950 2275);
FORCEPROP 2 LAST CDS_LIB pure_quanta_power
J 0
(-7800 2400);
DISPLAY INVISIBLE (-7800 2400);
FORCEPROP 1 LAST COMMENT_BODY TRUE
J 0
(-7775 2500);
DISPLAY 0.574468 (-7775 2500);
PAINT WHITE (-7775 2500);
DISPLAY INVISIBLE (-7775 2500);
FORCEADD QUANTA_TITLE_BLOCK_C..1
(-100 100);
FORCEPROP 0 LAST CDS_CON_LAST_MODIFIED Fri Mar 11 14:52:31 2022
J 0
(-1985 115);
DISPLAY INVISIBLE (-1985 115);
FORCEPROP 1 LAST CUSTOM_TXT_CDS <CON_LAST_MODIFIED>
J 0
(-1985 115);
DISPLAY 0.978723 (-1985 115);
FORCEPROP 2 LAST CUSTOM_TXT_CDS <XR_PAGE_TITLE>
J 0
(-7990 5350);
DISPLAY 0.638298 (-7990 5350);
PAINT PINK (-7990 5350);
DISPLAY INVISIBLE (-7990 5350);
FORCEPROP 1 LAST CUSTOM_TXT_CDS <NAME_2>
J 0
(-3275 150);
FORCEPROP 1 LAST CUSTOM_TXT_CDS <NAME_1>
J 0
(-3275 275);
FORCEPROP 1 LAST CUSTOM_TXT_CDS <Q_NUMBER>
J 0
(-1503 203);
DISPLAY 1.212766 (-1503 203);
FORCEPROP 1 LAST CUSTOM_TXT_CDS <Q_PROJ>
J 0
(-2482 202);
DISPLAY 1.212766 (-2482 202);
FORCEPROP 1 LAST CUSTOM_TXT_CDS <Q_REV>
J 0
(-284 203);
DISPLAY 1.212766 (-284 203);
FORCEPROP 1 LAST CUSTOM_TXT_CDS <CON_PAGE_NUM> OF <CON_TOTAL_PAGES>
J 0
(-546 118);
DISPLAY 0.978723 (-546 118);
FORCEPROP 1 LAST Q_TITLE CPU1 DDR CHE
J 0
(-9400 150);
DISPLAY 2.446809 (-9400 150);
PAINT GREEN (-9400 150);
FORCEPROP 1 LAST Q_DEPT BU9
J 1
(-3863 149);
DISPLAY 1.957447 (-3863 149);
PAINT GREEN (-3863 149);
FORCEPROP 2 LAST PAGE_BORDER TRUE
J 0
(-7990 5350);
DISPLAY 0.638298 (-7990 5350);
PAINT PINK (-7990 5350);
DISPLAY INVISIBLE (-7990 5350);
FORCEPROP 2 LAST CDS_LIB pure_quanta
J 0
(-100 100);
DISPLAY INVISIBLE (-100 100);
FORCEPROP 1 LAST CDS_LMAN_SYM_OUTLINE -9475,6775,100,-125
J 0
(-100 100);
DISPLAY 0.468085 (-100 100);
PAINT GREEN (-100 100);
DISPLAY INVISIBLE (-100 100);
FORCEPROP 1 LAST COMMENT_BODY TRUE
J 0
(-88 87);
DISPLAY 0.978723 (-88 87);
PAINT GREEN (-88 87);
DISPLAY INVISIBLE (-88 87);
FORCEPROP 2 LAST CDS_XR_PAGE_TITLE CR-41 : @T6G_MB_LIB.T6G(SCH_1):PAGE41
J 0
(-7990 5350);
DISPLAY 0.638298 (-7990 5350);
PAINT PINK (-7990 5350);
DISPLAY INVISIBLE (-7990 5350);
WIRE 17 -1 (-3375 6000)(-3375 5950);
WIRE 17 -1 (-3375 6000)(-2750 6000);
FORCEPROP 2 LAST SIG_NAME M_E_CPU1_SA_DQ<31:0>
J 2
(-2810 6010);
DISPLAY 0.489362 (-2810 6010);
WIRE 17 -1 (-3375 5950)(-3375 5900);
WIRE 17 -1 (-3375 5900)(-3375 5850);
WIRE 17 -1 (-3375 5850)(-3375 5800);
WIRE 17 -1 (-3375 5800)(-3375 5750);
WIRE 17 -1 (-3375 5450)(-3375 5400);
WIRE 17 -1 (-3375 5500)(-3375 5450);
WIRE 17 -1 (-3375 5400)(-3375 5350);
WIRE 17 -1 (-3375 5350)(-3375 5300);
WIRE 17 -1 (-3375 5550)(-3375 5500);
WIRE 17 -1 (-3375 5650)(-3375 5550);
WIRE 17 -1 (-3375 5300)(-3375 5250);
WIRE 17 -1 (-3375 5250)(-3375 5200);
WIRE 17 -1 (-3375 5700)(-3375 5650);
WIRE 17 -1 (-3375 5750)(-3375 5700);
WIRE 17 -1 (-3375 5100)(-3375 5200);
WIRE 17 -1 (-3375 5050)(-3375 5100);
WIRE 17 -1 (-3375 5000)(-3375 5050);
WIRE 17 -1 (-3375 4950)(-3375 5000);
WIRE 17 -1 (-3375 4950)(-3375 4900);
WIRE 17 -1 (-3375 4900)(-3375 4850);
WIRE 17 -1 (-3375 4850)(-3375 4800);
WIRE 17 -1 (-3375 4800)(-3375 4750);
WIRE 17 -1 (-3375 4750)(-3375 4650);
WIRE 17 -1 (-3375 4650)(-3375 4600);
WIRE 17 -1 (-3375 4600)(-3375 4550);
WIRE 17 -1 (-3375 4550)(-3375 4500);
WIRE 17 -1 (-3375 4450)(-3375 4500);
WIRE 17 -1 (-3375 4400)(-3375 4450);
WIRE 17 -1 (-3375 4350)(-3375 4400);
WIRE 17 -1 (-3375 4300)(-3375 4350);
WIRE 17 -1 (-3375 4200)(-3375 4150);
WIRE 17 -1 (-3375 4200)(-2750 4200);
FORCEPROP 2 LAST SIG_NAME M_E_CPU1_SB_DQ<31:0>
J 2
(-2810 4210);
DISPLAY 0.489362 (-2810 4210);
WIRE 17 -1 (-3375 4150)(-3375 4100);
WIRE 17 -1 (-3375 4100)(-3375 4050);
WIRE 17 -1 (-3375 4050)(-3375 4000);
WIRE 17 -1 (-3375 3300)(-3375 3400);
WIRE 17 -1 (-3375 3250)(-3375 3300);
WIRE 17 -1 (-3375 3450)(-3375 3400);
WIRE 17 -1 (-3375 3500)(-3375 3450);
WIRE 17 -1 (-3375 3200)(-3375 3250);
WIRE 17 -1 (-3375 3150)(-3375 3200);
WIRE 17 -1 (-3375 3550)(-3375 3500);
WIRE 17 -1 (-3375 3600)(-3375 3550);
WIRE 17 -1 (-3375 3150)(-3375 3100);
WIRE 17 -1 (-3375 3100)(-3375 3050);
WIRE 17 -1 (-3375 3650)(-3375 3600);
WIRE 17 -1 (-3375 3700)(-3375 3650);
WIRE 17 -1 (-3375 3050)(-3375 3000);
WIRE 17 -1 (-3375 3000)(-3375 2950);
WIRE 17 -1 (-3375 3750)(-3375 3700);
WIRE 17 -1 (-3375 3850)(-3375 3750);
WIRE 17 -1 (-3375 2950)(-3375 2850);
WIRE 17 -1 (-3375 2850)(-3375 2800);
WIRE 17 -1 (-3375 3900)(-3375 3850);
WIRE 17 -1 (-3375 3950)(-3375 3900);
WIRE 17 -1 (-3375 2800)(-3375 2750);
WIRE 17 -1 (-3375 2750)(-3375 2700);
WIRE 17 -1 (-3375 4000)(-3375 3950);
WIRE 17 -1 (-3375 2650)(-3375 2700);
WIRE 17 -1 (-3375 2600)(-3375 2650);
WIRE 17 -1 (-3375 2550)(-3375 2600);
WIRE 17 -1 (-3375 2500)(-3375 2550);
WIRE 17 -1 (-3375 2400)(-3375 2425);
WIRE 17 -1 (-3375 2400)(-3375 2350);
WIRE 17 -1 (-3375 2425)(-2875 2425);
FORCEPROP 2 LAST SIG_NAME M_E_CPU1_SA_CB<7:0>
J 2
(-2875 2435);
DISPLAY 0.489362 (-2875 2435);
WIRE 17 -1 (-3375 2300)(-3375 2350);
WIRE 17 -1 (-3375 2300)(-3375 2250);
WIRE 17 -1 (-3375 2200)(-3375 2250);
WIRE 17 -1 (-3375 2150)(-3375 2200);
WIRE 17 -1 (-3375 2100)(-3375 2150);
WIRE 17 -1 (-3375 2050)(-3375 2100);
WIRE 17 -1 (-3375 1650)(-3375 1700);
WIRE 17 -1 (-3375 1600)(-3375 1650);
WIRE 17 -1 (-3375 1700)(-3375 1750);
WIRE 17 -1 (-3375 1750)(-3375 1800);
WIRE 17 -1 (-3375 1850)(-3375 1800);
WIRE 17 -1 (-3375 1850)(-3375 1900);
WIRE 17 -1 (-3375 1950)(-3375 1900);
WIRE 17 -1 (-3375 1950)(-3375 1975);
WIRE 17 -1 (-3375 1975)(-2875 1975);
FORCEPROP 2 LAST SIG_NAME M_E_CPU1_SB_CB<7:0>
J 2
(-2875 1985);
DISPLAY 0.489362 (-2875 1985);
WIRE 17 -1 (-6100 5250)(-6100 5150);
WIRE 17 -1 (-6100 5250)(-6100 5350);
WIRE 17 -1 (-6100 5150)(-6100 5050);
WIRE 17 -1 (-6100 5350)(-6100 5450);
WIRE 17 -1 (-6100 5450)(-6100 5550);
WIRE 17 -1 (-6100 5650)(-6100 5550);
WIRE 17 -1 (-6100 5750)(-6100 5650);
WIRE 17 -1 (-6100 5850)(-6100 5750);
WIRE 17 -1 (-6100 5950)(-6100 5850);
FORCEPROP 2 LAST SIG_NAME M_E_CPU1_SA_DQS_DN<9:0>
J 2
(-6135 5960);
DISPLAY 0.489362 (-6135 5960);
WIRE 17 -1 (-5900 5700)(-5900 5600);
WIRE 17 -1 (-5900 5800)(-5900 5700);
WIRE 17 -1 (-5900 5500)(-5900 5600);
WIRE 17 -1 (-5900 5400)(-5900 5500);
WIRE 17 -1 (-5900 5900)(-5900 5800);
WIRE 17 -1 (-5900 6000)(-5900 5900);
WIRE 17 -1 (-5900 5300)(-5900 5400);
WIRE 17 -1 (-5900 5300)(-5900 5200);
WIRE 17 -1 (-5900 6000)(-6700 6000);
FORCEPROP 2 LAST SIG_NAME M_E_CPU1_SA_DQS_DP<9:0>
J 2
(-6135 6010);
DISPLAY 0.489362 (-6135 6010);
WIRE 17 -1 (-5900 5200)(-5900 5100);
WIRE 17 -1 (-6100 4700)(-6100 4600);
WIRE 17 -1 (-6100 4800)(-6100 4700);
WIRE 17 -1 (-6100 4600)(-6100 4500);
WIRE 17 -1 (-6100 4400)(-6100 4500);
WIRE 17 -1 (-6100 4900)(-6100 4800);
FORCEPROP 2 LAST SIG_NAME M_E_CPU1_SB_DQS_DN<9:0>
J 2
(-6135 4910);
DISPLAY 0.489362 (-6135 4910);
WIRE 17 -1 (-6100 4300)(-6100 4400);
WIRE 17 -1 (-6100 4200)(-6100 4300);
WIRE 17 -1 (-6100 4200)(-6100 4100);
WIRE 17 -1 (-5900 4950)(-5900 4850);
WIRE 17 -1 (-5900 4950)(-6700 4950);
FORCEPROP 2 LAST SIG_NAME M_E_CPU1_SB_DQS_DP<9:0>
J 2
(-6135 4960);
DISPLAY 0.489362 (-6135 4960);
WIRE 17 -1 (-6100 4100)(-6100 4000);
WIRE 17 -1 (-5900 4850)(-5900 4750);
WIRE 17 -1 (-5900 4750)(-5900 4650);
WIRE 17 -1 (-5900 4650)(-5900 4550);
WIRE 17 -1 (-5900 4450)(-5900 4550);
WIRE 17 -1 (-5900 4350)(-5900 4450);
WIRE 17 -1 (-5900 4250)(-5900 4350);
WIRE 17 -1 (-5900 4250)(-5900 4150);
WIRE 17 -1 (-5900 4150)(-5900 4050);
WIRE 17 -1 (-6100 3800)(-6100 3850);
WIRE 17 -1 (-6100 3750)(-6100 3800);
WIRE 17 -1 (-6100 3850)(-6600 3850);
FORCEPROP 2 LAST SIG_NAME M_E_CPU1_SA_CA<6:0>
J 0
(-6600 3860);
DISPLAY 0.489362 (-6600 3860);
WIRE 17 -1 (-6100 3400)(-6100 3450);
WIRE 17 -1 (-6100 3350)(-6100 3400);
WIRE 17 -1 (-6100 3450)(-6600 3450);
FORCEPROP 2 LAST SIG_NAME M_E_CPU1_SB_CA<6:0>
J 0
(-6600 3460);
DISPLAY 0.489362 (-6600 3460);
WIRE 17 -1 (-6100 3700)(-6100 3750);
WIRE 17 -1 (-6100 3300)(-6100 3350);
WIRE 17 -1 (-6100 3650)(-6100 3700);
WIRE 17 -1 (-6100 3600)(-6100 3650);
WIRE 17 -1 (-6100 3550)(-6100 3600);
WIRE 17 -1 (-6100 3250)(-6100 3300);
WIRE 17 -1 (-6100 3200)(-6100 3250);
WIRE 17 -1 (-6100 3150)(-6100 3200);
WIRE 17 -1 (-6100 5950)(-6700 5950);
WIRE 17 -1 (-6100 4900)(-6700 4900);
WIRE 16 -1 (-7550 2125)(-6825 2125);
FORCEPROP 2 LAST SIG_NAME M_E_CPU1_ALERT_N
J 0
(-7510 2135);
DISPLAY 0.489362 (-7510 2135);
WIRE 16 -1 (-6600 1175)(-5500 1175);
FORCEPROP 2 LAST SIG_NAME TP_M_E_CPU1_SA_TEST39E
J 0
(-6585 1185);
DISPLAY 0.489362 (-6585 1185);
FORCEPROP 2 LASTPROP $XRERR UNIQUE?
J 0
(-6840 1175);
DISPLAY 0.638298 (-6840 1175);
PAINT MONO (-6840 1175);
DISPLAY INVISIBLE (-6840 1175);
WIRE 16 -1 (-6625 2125)(-5500 2125);
FORCEPROP 2 LAST SIG_NAME M_E_CPU1_ALERT_R_N
J 0
(-6335 2135);
DISPLAY 0.489362 (-6335 2135);
FORCEPROP 2 LASTPROP $XRERR UNIQUE?
J 0
(-6575 2135);
DISPLAY 0.638298 (-6575 2135);
PAINT MONO (-6575 2135);
DISPLAY INVISIBLE (-6575 2135);
WIRE 16 -1 (-6600 2975)(-5500 2975);
FORCEPROP 2 LAST SIG_NAME M_E_CPU1_CLK_DP<0>
J 0
(-6600 2985);
DISPLAY 0.489362 (-6600 2985);
WIRE 16 -1 (-6600 2925)(-5500 2925);
FORCEPROP 2 LAST SIG_NAME M_E_CPU1_CLK_DN<0>
J 0
(-6600 2935);
DISPLAY 0.489362 (-6600 2935);
WIRE 16 -1 (-6600 2825)(-5500 2825);
FORCEPROP 2 LAST SIG_NAME M_E_CPU1_SA_CS_N<0>
J 0
(-6600 2835);
DISPLAY 0.489362 (-6600 2835);
WIRE 16 -1 (-6600 2675)(-5500 2675);
FORCEPROP 2 LAST SIG_NAME M_E_CPU1_SA_RSP<0>
J 0
(-6600 2685);
DISPLAY 0.489362 (-6600 2685);
WIRE 16 -1 (-6600 2775)(-5500 2775);
FORCEPROP 2 LAST SIG_NAME M_E_CPU1_SA_CS_N<1>
J 0
(-6600 2785);
DISPLAY 0.489362 (-6600 2785);
WIRE 16 -1 (-6600 2575)(-5500 2575);
FORCEPROP 2 LAST SIG_NAME M_E_CPU1_SA_PAR
J 0
(-6600 2585);
DISPLAY 0.489362 (-6600 2585);
WIRE 16 -1 (-6600 2425)(-5500 2425);
FORCEPROP 2 LAST SIG_NAME M_E_CPU1_SB_CS_N<1>
J 0
(-6600 2435);
DISPLAY 0.489362 (-6600 2435);
WIRE 16 -1 (-6600 2475)(-5500 2475);
FORCEPROP 2 LAST SIG_NAME M_E_CPU1_SB_CS_N<0>
J 0
(-6600 2485);
DISPLAY 0.489362 (-6600 2485);
WIRE 16 -1 (-6600 2325)(-5500 2325);
FORCEPROP 2 LAST SIG_NAME M_E_CPU1_SB_RSP<0>
J 0
(-6600 2335);
DISPLAY 0.489362 (-6600 2335);
WIRE 16 -1 (-6600 2225)(-5500 2225);
FORCEPROP 2 LAST SIG_NAME M_E_CPU1_SB_PAR
J 0
(-6600 2235);
DISPLAY 0.489362 (-6600 2235);
WIRE 16 -1 (-6600 2025)(-5500 2025);
FORCEPROP 2 LAST SIG_NAME M_E_CPU1_RESET_N
J 0
(-6600 2035);
DISPLAY 0.489362 (-6600 2035);
WIRE 16 -1 (-5800 4025)(-5500 4025);
WIRE 16 -1 (-6000 3125)(-5500 3125);
WIRE 16 -1 (-6000 3525)(-5500 3525);
WIRE 16 -1 (-6000 3175)(-5500 3175);
WIRE 16 -1 (-6000 3575)(-5500 3575);
WIRE 16 -1 (-6000 3225)(-5500 3225);
WIRE 16 -1 (-6000 3625)(-5500 3625);
WIRE 16 -1 (-6000 3275)(-5500 3275);
WIRE 16 -1 (-6000 3675)(-5500 3675);
WIRE 16 -1 (-6000 3325)(-5500 3325);
WIRE 16 -1 (-6000 3725)(-5500 3725);
WIRE 16 -1 (-6000 3375)(-5500 3375);
WIRE 16 -1 (-6000 3975)(-5500 3975);
WIRE 16 -1 (-6000 3775)(-5500 3775);
WIRE 16 -1 (-6000 3425)(-5500 3425);
WIRE 16 -1 (-6000 4075)(-5500 4075);
WIRE 16 -1 (-6000 3825)(-5500 3825);
WIRE 16 -1 (-6000 4775)(-5500 4775);
WIRE 16 -1 (-6000 4875)(-5500 4875);
WIRE 16 -1 (-5800 4125)(-5500 4125);
WIRE 16 -1 (-5800 4225)(-5500 4225);
WIRE 16 -1 (-5800 4325)(-5500 4325);
WIRE 16 -1 (-5800 4425)(-5500 4425);
WIRE 16 -1 (-5800 4525)(-5500 4525);
WIRE 16 -1 (-5800 5075)(-5500 5075);
WIRE 16 -1 (-5800 4625)(-5500 4625);
WIRE 16 -1 (-6000 4175)(-5500 4175);
WIRE 16 -1 (-5800 4725)(-5500 4725);
WIRE 16 -1 (-6000 4275)(-5500 4275);
WIRE 16 -1 (-5800 4825)(-5500 4825);
WIRE 16 -1 (-6000 4375)(-5500 4375);
WIRE 16 -1 (-5800 4925)(-5500 4925);
WIRE 16 -1 (-6000 4475)(-5500 4475);
WIRE 16 -1 (-6000 5025)(-5500 5025);
WIRE 16 -1 (-6000 4575)(-5500 4575);
WIRE 16 -1 (-6000 4675)(-5500 4675);
WIRE 16 -1 (-5800 5675)(-5500 5675);
WIRE 16 -1 (-6000 5225)(-5500 5225);
WIRE 16 -1 (-5800 5775)(-5500 5775);
WIRE 16 -1 (-6000 5325)(-5500 5325);
WIRE 16 -1 (-5800 5875)(-5500 5875);
WIRE 16 -1 (-6000 5425)(-5500 5425);
WIRE 16 -1 (-5800 5975)(-5500 5975);
WIRE 16 -1 (-6000 5525)(-5500 5525);
WIRE 16 -1 (-6000 5625)(-5500 5625);
WIRE 16 -1 (-6000 5725)(-5500 5725);
WIRE 16 -1 (-6000 5825)(-5500 5825);
WIRE 16 -1 (-6000 5925)(-5500 5925);
WIRE 16 -1 (-5800 5175)(-5500 5175);
WIRE 16 -1 (-5800 5275)(-5500 5275);
WIRE 16 -1 (-5800 5375)(-5500 5375);
WIRE 16 -1 (-5800 5475)(-5500 5475);
WIRE 16 -1 (-5800 5575)(-5500 5575);
WIRE 16 -1 (-6000 5125)(-5500 5125);
WIRE 16 -1 (-3900 1675)(-3475 1675);
WIRE 16 -1 (-3900 1725)(-3475 1725);
WIRE 16 -1 (-3900 1775)(-3475 1775);
WIRE 16 -1 (-3900 1825)(-3475 1825);
WIRE 16 -1 (-3900 2025)(-3475 2025);
WIRE 16 -1 (-3900 1875)(-3475 1875);
WIRE 16 -1 (-3900 1925)(-3475 1925);
WIRE 16 -1 (-3900 1575)(-3475 1575);
WIRE 16 -1 (-3900 1625)(-3475 1625);
WIRE 16 -1 (-3900 2775)(-3475 2775);
WIRE 16 -1 (-3900 2825)(-3475 2825);
WIRE 16 -1 (-3900 2925)(-3475 2925);
WIRE 16 -1 (-3900 2975)(-3475 2975);
WIRE 16 -1 (-3900 3025)(-3475 3025);
WIRE 16 -1 (-3900 2075)(-3475 2075);
WIRE 16 -1 (-3900 2475)(-3475 2475);
WIRE 16 -1 (-3900 2125)(-3475 2125);
WIRE 16 -1 (-3900 2525)(-3475 2525);
WIRE 16 -1 (-3900 2175)(-3475 2175);
WIRE 16 -1 (-3900 2225)(-3475 2225);
WIRE 16 -1 (-3900 2275)(-3475 2275);
WIRE 16 -1 (-3900 2325)(-3475 2325);
WIRE 16 -1 (-3900 2375)(-3475 2375);
WIRE 16 -1 (-3900 2575)(-3475 2575);
WIRE 16 -1 (-3900 2625)(-3475 2625);
WIRE 16 -1 (-3900 2675)(-3475 2675);
WIRE 16 -1 (-3900 2725)(-3475 2725);
WIRE 16 -1 (-3900 3425)(-3475 3425);
WIRE 16 -1 (-3900 3475)(-3475 3475);
WIRE 16 -1 (-3900 3525)(-3475 3525);
WIRE 16 -1 (-3900 3675)(-3475 3675);
WIRE 16 -1 (-3900 3575)(-3475 3575);
WIRE 16 -1 (-3900 3725)(-3475 3725);
WIRE 16 -1 (-3900 3625)(-3475 3625);
WIRE 16 -1 (-3900 3825)(-3475 3825);
WIRE 16 -1 (-3900 3075)(-3475 3075);
WIRE 16 -1 (-3900 3875)(-3475 3875);
WIRE 16 -1 (-3900 3925)(-3475 3925);
WIRE 16 -1 (-3900 3975)(-3475 3975);
WIRE 16 -1 (-3900 4025)(-3475 4025);
WIRE 16 -1 (-3900 4075)(-3475 4075);
WIRE 16 -1 (-3900 3125)(-3475 3125);
WIRE 16 -1 (-3900 3175)(-3475 3175);
WIRE 16 -1 (-3900 3225)(-3475 3225);
WIRE 16 -1 (-3900 3275)(-3475 3275);
WIRE 16 -1 (-3900 3375)(-3475 3375);
WIRE 16 -1 (-3900 4925)(-3475 4925);
WIRE 16 -1 (-3900 4975)(-3475 4975);
WIRE 16 -1 (-3900 4375)(-3475 4375);
WIRE 16 -1 (-3900 5025)(-3475 5025);
WIRE 16 -1 (-3900 4425)(-3475 4425);
WIRE 16 -1 (-3900 5075)(-3475 5075);
WIRE 16 -1 (-3900 4475)(-3475 4475);
WIRE 16 -1 (-3900 4525)(-3475 4525);
WIRE 16 -1 (-3900 4575)(-3475 4575);
WIRE 16 -1 (-3900 4625)(-3475 4625);
WIRE 16 -1 (-3900 4725)(-3475 4725);
WIRE 16 -1 (-3900 4775)(-3475 4775);
WIRE 16 -1 (-3900 4825)(-3475 4825);
WIRE 16 -1 (-3900 4875)(-3475 4875);
WIRE 16 -1 (-3900 4275)(-3475 4275);
WIRE 16 -1 (-3900 4125)(-3475 4125);
WIRE 16 -1 (-3900 4325)(-3475 4325);
WIRE 16 -1 (-3900 4175)(-3475 4175);
WIRE 16 -1 (-3900 5475)(-3475 5475);
WIRE 16 -1 (-3900 5525)(-3475 5525);
WIRE 16 -1 (-3900 5175)(-3475 5175);
WIRE 16 -1 (-3900 5625)(-3475 5625);
WIRE 16 -1 (-3900 5225)(-3475 5225);
WIRE 16 -1 (-3900 5675)(-3475 5675);
WIRE 16 -1 (-3900 5275)(-3475 5275);
WIRE 16 -1 (-3900 5725)(-3475 5725);
WIRE 16 -1 (-3900 5325)(-3475 5325);
WIRE 16 -1 (-3900 5775)(-3475 5775);
WIRE 16 -1 (-3900 5375)(-3475 5375);
WIRE 16 -1 (-3900 5825)(-3475 5825);
WIRE 16 -1 (-3900 5425)(-3475 5425);
WIRE 16 -1 (-3900 5875)(-3475 5875);
WIRE 16 -1 (-3900 5925)(-3475 5925);
WIRE 16 -1 (-3900 5975)(-3475 5975);
QUIT
